FILE_TYPE = MACRO_DRAWING;
SET COLOR_WIRE YELLOW;
SET COLOR_PROP MONO;
SET COLOR_DOT WHITE;
SET COLOR_ARC YELLOW;
SET COLOR_BODY GREEN;
SET COLOR_NOTE MONO;
SET PROP_DISPLAY VALUE;
SET PAGE_NUMBER P245;
FORCEADD TAP..1
R 2
(-5900 3925);
FORCEPROP 3 LASTPIN (-5850 3925) SIG_NAME P3E_CPU0_PE2_SS_C_TXN<11>
J 0
(-5840 3935);
DISPLAY 0.659574 (-5840 3935);
PAINT MONO (-5840 3935);
DISPLAY INVISIBLE (-5840 3935);
FORCEPROP 1 LASTPIN (-5850 3925) BN 11
J 2
(-5838 3933);
DISPLAY 0.680851 (-5838 3933);
PAINT GREEN (-5838 3933);
FORCEPROP 1 LAST HDL_TAP TRUE
J 2
(-6225 3800);
DISPLAY 0.872340 (-6225 3800);
PAINT ORANGE (-6225 3800);
DISPLAY INVISIBLE (-6225 3800);
FORCEPROP 1 LAST BODY_TYPE PLUMBING
J 2
(-5900 3975);
DISPLAY 0.872340 (-5900 3975);
PAINT GREEN (-5900 3975);
DISPLAY INVISIBLE (-5900 3975);
FORCEPROP 2 LAST CDS_LIB mstr_standard
J 0
(-5900 3925);
PAINT MONO (-5900 3925);
DISPLAY INVISIBLE (-5900 3925);
FORCEPROP 1 LAST PATH I10
J 2
(-5898 3925);
DISPLAY 0.872340 (-5898 3925);
PAINT GREEN (-5898 3925);
DISPLAY INVISIBLE (-5898 3925);
FORCEADD TAP..1
R 2
(-5900 4125);
FORCEPROP 3 LASTPIN (-5850 4125) SIG_NAME P3E_CPU0_PE2_SS_C_TXN<10>
J 0
(-5840 4135);
DISPLAY 0.659574 (-5840 4135);
PAINT MONO (-5840 4135);
DISPLAY INVISIBLE (-5840 4135);
FORCEPROP 1 LASTPIN (-5850 4125) BN 10
J 2
(-5838 4133);
DISPLAY 0.680851 (-5838 4133);
PAINT GREEN (-5838 4133);
FORCEPROP 1 LAST HDL_TAP TRUE
J 2
(-6225 4000);
DISPLAY 0.872340 (-6225 4000);
PAINT ORANGE (-6225 4000);
DISPLAY INVISIBLE (-6225 4000);
FORCEPROP 1 LAST BODY_TYPE PLUMBING
J 2
(-5900 4175);
DISPLAY 0.872340 (-5900 4175);
PAINT GREEN (-5900 4175);
DISPLAY INVISIBLE (-5900 4175);
FORCEPROP 2 LAST CDS_LIB mstr_standard
J 0
(-5900 4125);
PAINT MONO (-5900 4125);
DISPLAY INVISIBLE (-5900 4125);
FORCEPROP 1 LAST PATH I11
J 2
(-5898 4125);
DISPLAY 0.872340 (-5898 4125);
PAINT GREEN (-5898 4125);
DISPLAY INVISIBLE (-5898 4125);
FORCEADD TAP..1
R 2
(-5900 4275);
FORCEPROP 3 LASTPIN (-5850 4275) SIG_NAME P3E_CPU0_PE2_SS_C_TXN<9>
J 0
(-5840 4285);
DISPLAY 0.659574 (-5840 4285);
PAINT MONO (-5840 4285);
DISPLAY INVISIBLE (-5840 4285);
FORCEPROP 1 LASTPIN (-5850 4275) BN 9
J 2
(-5838 4283);
DISPLAY 0.680851 (-5838 4283);
PAINT GREEN (-5838 4283);
FORCEPROP 1 LAST HDL_TAP TRUE
J 2
(-6225 4150);
DISPLAY 0.872340 (-6225 4150);
PAINT ORANGE (-6225 4150);
DISPLAY INVISIBLE (-6225 4150);
FORCEPROP 1 LAST BODY_TYPE PLUMBING
J 2
(-5900 4325);
DISPLAY 0.872340 (-5900 4325);
PAINT GREEN (-5900 4325);
DISPLAY INVISIBLE (-5900 4325);
FORCEPROP 2 LAST CDS_LIB mstr_standard
J 0
(-5900 4275);
PAINT MONO (-5900 4275);
DISPLAY INVISIBLE (-5900 4275);
FORCEPROP 1 LAST PATH I12
J 2
(-5898 4275);
DISPLAY 0.872340 (-5898 4275);
PAINT GREEN (-5898 4275);
DISPLAY INVISIBLE (-5898 4275);
FORCEADD TAP..1
R 2
(-5275 3525);
FORCEPROP 3 LASTPIN (-5225 3525) SIG_NAME P3E_CPU0_PE2_SS_C_TXP<14>
J 0
(-5215 3535);
DISPLAY 0.659574 (-5215 3535);
PAINT MONO (-5215 3535);
DISPLAY INVISIBLE (-5215 3535);
FORCEPROP 1 LASTPIN (-5225 3525) BN 14
J 2
(-5213 3533);
DISPLAY 0.680851 (-5213 3533);
PAINT GREEN (-5213 3533);
FORCEPROP 1 LAST HDL_TAP TRUE
J 2
(-5600 3400);
DISPLAY 0.872340 (-5600 3400);
PAINT ORANGE (-5600 3400);
DISPLAY INVISIBLE (-5600 3400);
FORCEPROP 1 LAST BODY_TYPE PLUMBING
J 2
(-5275 3575);
DISPLAY 0.872340 (-5275 3575);
PAINT GREEN (-5275 3575);
DISPLAY INVISIBLE (-5275 3575);
FORCEPROP 2 LAST CDS_LIB mstr_standard
J 0
(-5275 3525);
PAINT MONO (-5275 3525);
DISPLAY INVISIBLE (-5275 3525);
FORCEPROP 1 LAST PATH I13
J 2
(-5273 3525);
DISPLAY 0.872340 (-5273 3525);
PAINT GREEN (-5273 3525);
DISPLAY INVISIBLE (-5273 3525);
FORCEADD TAP..1
R 2
(-5275 3775);
FORCEPROP 3 LASTPIN (-5225 3775) SIG_NAME P3E_CPU0_PE2_SS_C_TXP<12>
J 0
(-5215 3785);
DISPLAY 0.659574 (-5215 3785);
PAINT MONO (-5215 3785);
DISPLAY INVISIBLE (-5215 3785);
FORCEPROP 1 LASTPIN (-5225 3775) BN 12
J 2
(-5213 3783);
DISPLAY 0.680851 (-5213 3783);
PAINT GREEN (-5213 3783);
FORCEPROP 1 LAST HDL_TAP TRUE
J 2
(-5600 3650);
DISPLAY 0.872340 (-5600 3650);
PAINT ORANGE (-5600 3650);
DISPLAY INVISIBLE (-5600 3650);
FORCEPROP 1 LAST BODY_TYPE PLUMBING
J 2
(-5275 3825);
DISPLAY 0.872340 (-5275 3825);
PAINT GREEN (-5275 3825);
DISPLAY INVISIBLE (-5275 3825);
FORCEPROP 2 LAST CDS_LIB mstr_standard
J 0
(-5275 3775);
PAINT MONO (-5275 3775);
DISPLAY INVISIBLE (-5275 3775);
FORCEPROP 1 LAST PATH I14
J 2
(-5273 3775);
DISPLAY 0.872340 (-5273 3775);
PAINT GREEN (-5273 3775);
DISPLAY INVISIBLE (-5273 3775);
FORCEADD TAP..1
R 2
(-5275 3625);
FORCEPROP 3 LASTPIN (-5225 3625) SIG_NAME P3E_CPU0_PE2_SS_C_TXP<13>
J 0
(-5215 3635);
DISPLAY 0.659574 (-5215 3635);
PAINT MONO (-5215 3635);
DISPLAY INVISIBLE (-5215 3635);
FORCEPROP 1 LASTPIN (-5225 3625) BN 13
J 2
(-5213 3633);
DISPLAY 0.680851 (-5213 3633);
PAINT GREEN (-5213 3633);
FORCEPROP 1 LAST HDL_TAP TRUE
J 2
(-5600 3500);
DISPLAY 0.872340 (-5600 3500);
PAINT ORANGE (-5600 3500);
DISPLAY INVISIBLE (-5600 3500);
FORCEPROP 1 LAST BODY_TYPE PLUMBING
J 2
(-5275 3675);
DISPLAY 0.872340 (-5275 3675);
PAINT GREEN (-5275 3675);
DISPLAY INVISIBLE (-5275 3675);
FORCEPROP 2 LAST CDS_LIB mstr_standard
J 0
(-5275 3625);
PAINT MONO (-5275 3625);
DISPLAY INVISIBLE (-5275 3625);
FORCEPROP 1 LAST PATH I15
J 2
(-5273 3625);
DISPLAY 0.872340 (-5273 3625);
PAINT GREEN (-5273 3625);
DISPLAY INVISIBLE (-5273 3625);
FORCEADD TAP..1
R 2
(-5275 3975);
FORCEPROP 3 LASTPIN (-5225 3975) SIG_NAME P3E_CPU0_PE2_SS_C_TXP<11>
J 0
(-5215 3985);
DISPLAY 0.659574 (-5215 3985);
PAINT MONO (-5215 3985);
DISPLAY INVISIBLE (-5215 3985);
FORCEPROP 1 LASTPIN (-5225 3975) BN 11
J 2
(-5213 3983);
DISPLAY 0.680851 (-5213 3983);
PAINT GREEN (-5213 3983);
FORCEPROP 1 LAST HDL_TAP TRUE
J 2
(-5600 3850);
DISPLAY 0.872340 (-5600 3850);
PAINT ORANGE (-5600 3850);
DISPLAY INVISIBLE (-5600 3850);
FORCEPROP 1 LAST BODY_TYPE PLUMBING
J 2
(-5275 4025);
DISPLAY 0.872340 (-5275 4025);
PAINT GREEN (-5275 4025);
DISPLAY INVISIBLE (-5275 4025);
FORCEPROP 2 LAST CDS_LIB mstr_standard
J 0
(-5275 3975);
PAINT MONO (-5275 3975);
DISPLAY INVISIBLE (-5275 3975);
FORCEPROP 1 LAST PATH I16
J 2
(-5273 3975);
DISPLAY 0.872340 (-5273 3975);
PAINT GREEN (-5273 3975);
DISPLAY INVISIBLE (-5273 3975);
FORCEADD TAP..1
R 2
(-5275 4075);
FORCEPROP 3 LASTPIN (-5225 4075) SIG_NAME P3E_CPU0_PE2_SS_C_TXP<10>
J 0
(-5215 4085);
DISPLAY 0.659574 (-5215 4085);
PAINT MONO (-5215 4085);
DISPLAY INVISIBLE (-5215 4085);
FORCEPROP 1 LASTPIN (-5225 4075) BN 10
J 2
(-5213 4083);
DISPLAY 0.680851 (-5213 4083);
PAINT GREEN (-5213 4083);
FORCEPROP 1 LAST HDL_TAP TRUE
J 2
(-5600 3950);
DISPLAY 0.872340 (-5600 3950);
PAINT ORANGE (-5600 3950);
DISPLAY INVISIBLE (-5600 3950);
FORCEPROP 1 LAST BODY_TYPE PLUMBING
J 2
(-5275 4125);
DISPLAY 0.872340 (-5275 4125);
PAINT GREEN (-5275 4125);
DISPLAY INVISIBLE (-5275 4125);
FORCEPROP 2 LAST CDS_LIB mstr_standard
J 0
(-5275 4075);
PAINT MONO (-5275 4075);
DISPLAY INVISIBLE (-5275 4075);
FORCEPROP 1 LAST PATH I17
J 2
(-5273 4075);
DISPLAY 0.872340 (-5273 4075);
PAINT GREEN (-5273 4075);
DISPLAY INVISIBLE (-5273 4075);
FORCEADD TAP..1
R 2
(-5275 4225);
FORCEPROP 3 LASTPIN (-5225 4225) SIG_NAME P3E_CPU0_PE2_SS_C_TXP<9>
J 0
(-5215 4235);
DISPLAY 0.659574 (-5215 4235);
PAINT MONO (-5215 4235);
DISPLAY INVISIBLE (-5215 4235);
FORCEPROP 1 LASTPIN (-5225 4225) BN 9
J 2
(-5213 4233);
DISPLAY 0.680851 (-5213 4233);
PAINT GREEN (-5213 4233);
FORCEPROP 1 LAST HDL_TAP TRUE
J 2
(-5600 4100);
DISPLAY 0.872340 (-5600 4100);
PAINT ORANGE (-5600 4100);
DISPLAY INVISIBLE (-5600 4100);
FORCEPROP 1 LAST BODY_TYPE PLUMBING
J 2
(-5275 4275);
DISPLAY 0.872340 (-5275 4275);
PAINT GREEN (-5275 4275);
DISPLAY INVISIBLE (-5275 4275);
FORCEPROP 2 LAST CDS_LIB mstr_standard
J 0
(-5275 4225);
PAINT MONO (-5275 4225);
DISPLAY INVISIBLE (-5275 4225);
FORCEPROP 1 LAST PATH I18
J 2
(-5273 4225);
DISPLAY 0.872340 (-5273 4225);
PAINT GREEN (-5273 4225);
DISPLAY INVISIBLE (-5273 4225);
FORCEADD GND..1
(-4725 2825);
FORCEPROP 3 LASTPIN (-4725 2875) SIG_NAME GND\g
J 0
(-4715 2885);
DISPLAY 0.659574 (-4715 2885);
PAINT MONO (-4715 2885);
DISPLAY INVISIBLE (-4715 2885);
FORCEPROP 1 LAST HDL_POWER GND
J 0
(-4725 3050);
DISPLAY 0.893617 (-4725 3050);
PAINT GREEN (-4725 3050);
DISPLAY INVISIBLE (-4725 3050);
FORCEPROP 1 LAST BODY_TYPE PLUMBING
J 0
(-4770 2782);
DISPLAY 0.340426 (-4770 2782);
PAINT GREEN (-4770 2782);
DISPLAY INVISIBLE (-4770 2782);
FORCEPROP 2 LAST ROOM PVPP_KLM_VR
J 0
(-5375 2975);
PAINT GREEN (-5375 2975);
DISPLAY INVISIBLE (-5375 2975);
FORCEPROP 1 LAST SIZE 1B
J 0
(-4650 2850);
DISPLAY 0.893617 (-4650 2850);
PAINT GREEN (-4650 2850);
DISPLAY INVISIBLE (-4650 2850);
FORCEPROP 1 LAST VOLTAGE 0
J 0
(-4725 2900);
PAINT SKYBLUE (-4725 2900);
DISPLAY INVISIBLE (-4725 2900);
FORCEPROP 2 LAST BOM_COST PVPP_KLM_VR
J 0
(-5625 2975);
DISPLAY 1.042553 (-5625 2975);
PAINT WHITE (-5625 2975);
DISPLAY INVISIBLE (-5625 2975);
FORCEPROP 2 LAST CDS_LIB mstr_symbols
J 0
(-4725 2825);
PAINT MONO (-4725 2825);
DISPLAY INVISIBLE (-4725 2825);
FORCEPROP 1 LAST PATH I19
J 0
(-4650 2825);
DISPLAY 0.872340 (-4650 2825);
PAINT AQUA (-4650 2825);
DISPLAY INVISIBLE (-4650 2825);
FORCEADD GND..1
(-4275 2625);
FORCEPROP 3 LASTPIN (-4275 2675) SIG_NAME GND\g
J 0
(-4265 2685);
DISPLAY 0.659574 (-4265 2685);
PAINT MONO (-4265 2685);
DISPLAY INVISIBLE (-4265 2685);
FORCEPROP 1 LAST HDL_POWER GND
J 0
(-4275 2850);
DISPLAY 0.893617 (-4275 2850);
PAINT GREEN (-4275 2850);
DISPLAY INVISIBLE (-4275 2850);
FORCEPROP 1 LAST BODY_TYPE PLUMBING
J 0
(-4320 2582);
DISPLAY 0.340426 (-4320 2582);
PAINT GREEN (-4320 2582);
DISPLAY INVISIBLE (-4320 2582);
FORCEPROP 2 LAST BOM_COST PVPP_KLM_VR
J 0
(-5175 2775);
DISPLAY 1.042553 (-5175 2775);
PAINT WHITE (-5175 2775);
DISPLAY INVISIBLE (-5175 2775);
FORCEPROP 1 LAST VOLTAGE 0
J 0
(-4275 2700);
PAINT SKYBLUE (-4275 2700);
DISPLAY INVISIBLE (-4275 2700);
FORCEPROP 1 LAST SIZE 1B
J 0
(-4200 2650);
DISPLAY 0.893617 (-4200 2650);
PAINT GREEN (-4200 2650);
DISPLAY INVISIBLE (-4200 2650);
FORCEPROP 2 LAST ROOM PVPP_KLM_VR
J 0
(-4925 2775);
PAINT GREEN (-4925 2775);
DISPLAY INVISIBLE (-4925 2775);
FORCEPROP 2 LAST CDS_LIB mstr_symbols
J 0
(-4275 2625);
PAINT MONO (-4275 2625);
DISPLAY INVISIBLE (-4275 2625);
FORCEPROP 1 LAST PATH I20
J 0
(-4200 2625);
DISPLAY 0.872340 (-4200 2625);
PAINT AQUA (-4200 2625);
DISPLAY INVISIBLE (-4200 2625);
FORCEADD OFFPAGE..1
(-6900 4550);
FORCEPROP 2 LAST $XR0 105 
J 0
(-7152 4550);
DISPLAY 0.638298 (-7152 4550);
PAINT MONO (-7152 4550);
FORCEPROP 1 LAST COMMENT_BODY TRUE
J 0
(-6775 4450);
DISPLAY 0.872340 (-6775 4450);
PAINT GREEN (-6775 4450);
DISPLAY INVISIBLE (-6775 4450);
FORCEPROP 1 LAST OFFPAGE TRUE
J 0
(-6575 4425);
DISPLAY 0.872340 (-6575 4425);
PAINT GREEN (-6575 4425);
DISPLAY INVISIBLE (-6575 4425);
FORCEPROP 2 LAST CDS_LIB mstr_standard
J 0
(-6900 4550);
PAINT MONO (-6900 4550);
DISPLAY INVISIBLE (-6900 4550);
FORCEPROP 2 LAST PATH I21
J 0
(-7150 4600);
DISPLAY 1.021277 (-7150 4600);
PAINT ORANGE (-7150 4600);
DISPLAY INVISIBLE (-7150 4600);
FORCEADD OFFPAGE..1
(-6900 4775);
FORCEPROP 2 LAST $XR0 105 
J 0
(-7152 4775);
DISPLAY 0.638298 (-7152 4775);
PAINT MONO (-7152 4775);
FORCEPROP 1 LAST COMMENT_BODY TRUE
J 0
(-6775 4675);
DISPLAY 0.872340 (-6775 4675);
PAINT GREEN (-6775 4675);
DISPLAY INVISIBLE (-6775 4675);
FORCEPROP 1 LAST OFFPAGE TRUE
J 0
(-6575 4650);
DISPLAY 0.872340 (-6575 4650);
PAINT GREEN (-6575 4650);
DISPLAY INVISIBLE (-6575 4650);
FORCEPROP 2 LAST CDS_LIB mstr_standard
J 0
(-6900 4775);
PAINT MONO (-6900 4775);
DISPLAY INVISIBLE (-6900 4775);
FORCEPROP 2 LAST PATH I22
J 0
(-7150 4825);
DISPLAY 1.021277 (-7150 4825);
PAINT ORANGE (-7150 4825);
DISPLAY INVISIBLE (-7150 4825);
FORCEADD GND..1
(-4425 4575);
FORCEPROP 3 LASTPIN (-4425 4625) SIG_NAME GND\g
J 0
(-4415 4635);
DISPLAY 0.659574 (-4415 4635);
PAINT MONO (-4415 4635);
DISPLAY INVISIBLE (-4415 4635);
FORCEPROP 1 LAST HDL_POWER GND
J 0
(-4425 4800);
DISPLAY 0.893617 (-4425 4800);
PAINT GREEN (-4425 4800);
DISPLAY INVISIBLE (-4425 4800);
FORCEPROP 1 LAST BODY_TYPE PLUMBING
J 0
(-4470 4532);
DISPLAY 0.340426 (-4470 4532);
PAINT GREEN (-4470 4532);
DISPLAY INVISIBLE (-4470 4532);
FORCEPROP 2 LAST CDS_LIB mstr_symbols
J 0
(-4425 4575);
PAINT MONO (-4425 4575);
DISPLAY INVISIBLE (-4425 4575);
FORCEPROP 2 LAST ROOM PVPP_KLM_VR
J 0
(-5075 4725);
PAINT GREEN (-5075 4725);
DISPLAY INVISIBLE (-5075 4725);
FORCEPROP 1 LAST SIZE 1B
J 0
(-4350 4600);
DISPLAY 0.893617 (-4350 4600);
PAINT GREEN (-4350 4600);
DISPLAY INVISIBLE (-4350 4600);
FORCEPROP 1 LAST VOLTAGE 0
J 0
(-4425 4650);
PAINT SKYBLUE (-4425 4650);
DISPLAY INVISIBLE (-4425 4650);
FORCEPROP 2 LAST BOM_COST PVPP_KLM_VR
J 0
(-5325 4725);
DISPLAY 1.042553 (-5325 4725);
PAINT WHITE (-5325 4725);
DISPLAY INVISIBLE (-5325 4725);
FORCEPROP 1 LAST PATH I25
J 0
(-4350 4575);
DISPLAY 0.872340 (-4350 4575);
PAINT AQUA (-4350 4575);
DISPLAY INVISIBLE (-4350 4575);
FORCEADD GND..1
(-3375 2625);
FORCEPROP 3 LASTPIN (-3375 2675) SIG_NAME GND\g
J 0
(-3365 2685);
DISPLAY 0.659574 (-3365 2685);
PAINT MONO (-3365 2685);
DISPLAY INVISIBLE (-3365 2685);
FORCEPROP 1 LAST HDL_POWER GND
J 0
(-3375 2850);
DISPLAY 0.893617 (-3375 2850);
PAINT GREEN (-3375 2850);
DISPLAY INVISIBLE (-3375 2850);
FORCEPROP 1 LAST BODY_TYPE PLUMBING
J 0
(-3420 2582);
DISPLAY 0.340426 (-3420 2582);
PAINT GREEN (-3420 2582);
DISPLAY INVISIBLE (-3420 2582);
FORCEPROP 2 LAST BOM_COST PVPP_KLM_VR
J 0
(-4275 2775);
DISPLAY 1.042553 (-4275 2775);
PAINT WHITE (-4275 2775);
DISPLAY INVISIBLE (-4275 2775);
FORCEPROP 1 LAST VOLTAGE 0
J 0
(-3375 2700);
PAINT SKYBLUE (-3375 2700);
DISPLAY INVISIBLE (-3375 2700);
FORCEPROP 1 LAST SIZE 1B
J 0
(-3300 2650);
DISPLAY 0.893617 (-3300 2650);
PAINT GREEN (-3300 2650);
DISPLAY INVISIBLE (-3300 2650);
FORCEPROP 2 LAST ROOM PVPP_KLM_VR
J 0
(-4025 2775);
PAINT GREEN (-4025 2775);
DISPLAY INVISIBLE (-4025 2775);
FORCEPROP 2 LAST CDS_LIB mstr_symbols
J 0
(-3375 2625);
PAINT MONO (-3375 2625);
DISPLAY INVISIBLE (-3375 2625);
FORCEPROP 1 LAST PATH I27
J 0
(-3300 2625);
DISPLAY 0.872340 (-3300 2625);
PAINT AQUA (-3300 2625);
DISPLAY INVISIBLE (-3300 2625);
FORCEADD TAP..6
R 2
(-2475 3325);
FORCEPROP 3 LASTPIN (-2525 3325) SIG_NAME P3E_CPU0_PE2_SS_RXN<15>
J 0
(-2515 3335);
DISPLAY 0.659574 (-2515 3335);
PAINT MONO (-2515 3335);
DISPLAY INVISIBLE (-2515 3335);
FORCEPROP 1 LASTPIN (-2525 3325) BN 15
J 2
(-2473 3333);
DISPLAY 0.680851 (-2473 3333);
PAINT GREEN (-2473 3333);
FORCEPROP 1 LAST HDL_TAP TRUE
J 2
(-2800 3200);
DISPLAY 0.872340 (-2800 3200);
PAINT ORANGE (-2800 3200);
DISPLAY INVISIBLE (-2800 3200);
FORCEPROP 1 LAST BODY_TYPE PLUMBING
J 2
(-2475 3275);
DISPLAY 0.872340 (-2475 3275);
PAINT GREEN (-2475 3275);
DISPLAY INVISIBLE (-2475 3275);
FORCEPROP 2 LAST CDS_LIB mstr_standard
J 0
(-2475 3325);
PAINT MONO (-2475 3325);
DISPLAY INVISIBLE (-2475 3325);
FORCEPROP 1 LAST PATH I29
J 2
(-2473 3325);
DISPLAY 0.872340 (-2473 3325);
PAINT GREEN (-2473 3325);
DISPLAY INVISIBLE (-2473 3325);
FORCEADD TAP..6
R 2
(-2275 3275);
FORCEPROP 3 LASTPIN (-2325 3275) SIG_NAME P3E_CPU0_PE2_SS_RXP<15>
J 0
(-2315 3285);
DISPLAY 0.659574 (-2315 3285);
PAINT MONO (-2315 3285);
DISPLAY INVISIBLE (-2315 3285);
FORCEPROP 1 LASTPIN (-2325 3275) BN 15
J 2
(-2273 3283);
DISPLAY 0.680851 (-2273 3283);
PAINT GREEN (-2273 3283);
FORCEPROP 1 LAST HDL_TAP TRUE
J 2
(-2600 3150);
DISPLAY 0.872340 (-2600 3150);
PAINT ORANGE (-2600 3150);
DISPLAY INVISIBLE (-2600 3150);
FORCEPROP 1 LAST BODY_TYPE PLUMBING
J 2
(-2275 3225);
DISPLAY 0.872340 (-2275 3225);
PAINT GREEN (-2275 3225);
DISPLAY INVISIBLE (-2275 3225);
FORCEPROP 2 LAST CDS_LIB mstr_standard
J 0
(-2275 3275);
PAINT MONO (-2275 3275);
DISPLAY INVISIBLE (-2275 3275);
FORCEPROP 1 LAST PATH I30
J 2
(-2273 3275);
DISPLAY 0.872340 (-2273 3275);
PAINT GREEN (-2273 3275);
DISPLAY INVISIBLE (-2273 3275);
FORCEADD TAP..6
R 2
(-2475 3575);
FORCEPROP 3 LASTPIN (-2525 3575) SIG_NAME P3E_CPU0_PE2_SS_RXN<13>
J 0
(-2515 3585);
DISPLAY 0.659574 (-2515 3585);
PAINT MONO (-2515 3585);
DISPLAY INVISIBLE (-2515 3585);
FORCEPROP 1 LASTPIN (-2525 3575) BN 13
J 2
(-2473 3583);
DISPLAY 0.680851 (-2473 3583);
PAINT GREEN (-2473 3583);
FORCEPROP 1 LAST HDL_TAP TRUE
J 2
(-2800 3450);
DISPLAY 0.872340 (-2800 3450);
PAINT ORANGE (-2800 3450);
DISPLAY INVISIBLE (-2800 3450);
FORCEPROP 1 LAST BODY_TYPE PLUMBING
J 2
(-2475 3525);
DISPLAY 0.872340 (-2475 3525);
PAINT GREEN (-2475 3525);
DISPLAY INVISIBLE (-2475 3525);
FORCEPROP 2 LAST CDS_LIB mstr_standard
J 0
(-2475 3575);
PAINT MONO (-2475 3575);
DISPLAY INVISIBLE (-2475 3575);
FORCEPROP 1 LAST PATH I31
J 2
(-2473 3575);
DISPLAY 0.872340 (-2473 3575);
PAINT GREEN (-2473 3575);
DISPLAY INVISIBLE (-2473 3575);
FORCEADD TAP..6
R 2
(-2475 3475);
FORCEPROP 3 LASTPIN (-2525 3475) SIG_NAME P3E_CPU0_PE2_SS_RXN<14>
J 0
(-2515 3485);
DISPLAY 0.659574 (-2515 3485);
PAINT MONO (-2515 3485);
DISPLAY INVISIBLE (-2515 3485);
FORCEPROP 1 LASTPIN (-2525 3475) BN 14
J 2
(-2473 3483);
DISPLAY 0.680851 (-2473 3483);
PAINT GREEN (-2473 3483);
FORCEPROP 1 LAST HDL_TAP TRUE
J 2
(-2800 3350);
DISPLAY 0.872340 (-2800 3350);
PAINT ORANGE (-2800 3350);
DISPLAY INVISIBLE (-2800 3350);
FORCEPROP 1 LAST BODY_TYPE PLUMBING
J 2
(-2475 3425);
DISPLAY 0.872340 (-2475 3425);
PAINT GREEN (-2475 3425);
DISPLAY INVISIBLE (-2475 3425);
FORCEPROP 2 LAST CDS_LIB mstr_standard
J 0
(-2475 3475);
PAINT MONO (-2475 3475);
DISPLAY INVISIBLE (-2475 3475);
FORCEPROP 1 LAST PATH I32
J 2
(-2473 3475);
DISPLAY 0.872340 (-2473 3475);
PAINT GREEN (-2473 3475);
DISPLAY INVISIBLE (-2473 3475);
FORCEADD TAP..6
R 2
(-2475 3775);
FORCEPROP 3 LASTPIN (-2525 3775) SIG_NAME P3E_CPU0_PE2_SS_RXN<12>
J 0
(-2515 3785);
DISPLAY 0.659574 (-2515 3785);
PAINT MONO (-2515 3785);
DISPLAY INVISIBLE (-2515 3785);
FORCEPROP 1 LASTPIN (-2525 3775) BN 12
J 2
(-2473 3783);
DISPLAY 0.680851 (-2473 3783);
PAINT GREEN (-2473 3783);
FORCEPROP 1 LAST HDL_TAP TRUE
J 2
(-2800 3650);
DISPLAY 0.872340 (-2800 3650);
PAINT ORANGE (-2800 3650);
DISPLAY INVISIBLE (-2800 3650);
FORCEPROP 1 LAST BODY_TYPE PLUMBING
J 2
(-2475 3725);
DISPLAY 0.872340 (-2475 3725);
PAINT GREEN (-2475 3725);
DISPLAY INVISIBLE (-2475 3725);
FORCEPROP 2 LAST CDS_LIB mstr_standard
J 0
(-2475 3775);
PAINT MONO (-2475 3775);
DISPLAY INVISIBLE (-2475 3775);
FORCEPROP 1 LAST PATH I33
J 2
(-2473 3775);
DISPLAY 0.872340 (-2473 3775);
PAINT GREEN (-2473 3775);
DISPLAY INVISIBLE (-2473 3775);
FORCEADD TAP..6
R 2
(-2475 3925);
FORCEPROP 3 LASTPIN (-2525 3925) SIG_NAME P3E_CPU0_PE2_SS_RXN<11>
J 0
(-2515 3935);
DISPLAY 0.659574 (-2515 3935);
PAINT MONO (-2515 3935);
DISPLAY INVISIBLE (-2515 3935);
FORCEPROP 1 LASTPIN (-2525 3925) BN 11
J 2
(-2473 3933);
DISPLAY 0.680851 (-2473 3933);
PAINT GREEN (-2473 3933);
FORCEPROP 1 LAST HDL_TAP TRUE
J 2
(-2800 3800);
DISPLAY 0.872340 (-2800 3800);
PAINT ORANGE (-2800 3800);
DISPLAY INVISIBLE (-2800 3800);
FORCEPROP 1 LAST BODY_TYPE PLUMBING
J 2
(-2475 3875);
DISPLAY 0.872340 (-2475 3875);
PAINT GREEN (-2475 3875);
DISPLAY INVISIBLE (-2475 3875);
FORCEPROP 2 LAST CDS_LIB mstr_standard
J 0
(-2475 3925);
PAINT MONO (-2475 3925);
DISPLAY INVISIBLE (-2475 3925);
FORCEPROP 1 LAST PATH I34
J 2
(-2473 3925);
DISPLAY 0.872340 (-2473 3925);
PAINT GREEN (-2473 3925);
DISPLAY INVISIBLE (-2473 3925);
FORCEADD TAP..6
R 2
(-2475 4075);
FORCEPROP 3 LASTPIN (-2525 4075) SIG_NAME P3E_CPU0_PE2_SS_RXN<10>
J 0
(-2515 4085);
DISPLAY 0.659574 (-2515 4085);
PAINT MONO (-2515 4085);
DISPLAY INVISIBLE (-2515 4085);
FORCEPROP 1 LASTPIN (-2525 4075) BN 10
J 2
(-2473 4083);
DISPLAY 0.680851 (-2473 4083);
PAINT GREEN (-2473 4083);
FORCEPROP 1 LAST HDL_TAP TRUE
J 2
(-2800 3950);
DISPLAY 0.872340 (-2800 3950);
PAINT ORANGE (-2800 3950);
DISPLAY INVISIBLE (-2800 3950);
FORCEPROP 1 LAST BODY_TYPE PLUMBING
J 2
(-2475 4025);
DISPLAY 0.872340 (-2475 4025);
PAINT GREEN (-2475 4025);
DISPLAY INVISIBLE (-2475 4025);
FORCEPROP 2 LAST CDS_LIB mstr_standard
J 0
(-2475 4075);
PAINT MONO (-2475 4075);
DISPLAY INVISIBLE (-2475 4075);
FORCEPROP 1 LAST PATH I35
J 2
(-2473 4075);
DISPLAY 0.872340 (-2473 4075);
PAINT GREEN (-2473 4075);
DISPLAY INVISIBLE (-2473 4075);
FORCEADD TAP..6
R 2
(-2475 4225);
FORCEPROP 3 LASTPIN (-2525 4225) SIG_NAME P3E_CPU0_PE2_SS_RXN<9>
J 0
(-2515 4235);
DISPLAY 0.659574 (-2515 4235);
PAINT MONO (-2515 4235);
DISPLAY INVISIBLE (-2515 4235);
FORCEPROP 1 LASTPIN (-2525 4225) BN 9
J 2
(-2473 4233);
DISPLAY 0.680851 (-2473 4233);
PAINT GREEN (-2473 4233);
FORCEPROP 1 LAST HDL_TAP TRUE
J 2
(-2800 4100);
DISPLAY 0.872340 (-2800 4100);
PAINT ORANGE (-2800 4100);
DISPLAY INVISIBLE (-2800 4100);
FORCEPROP 1 LAST BODY_TYPE PLUMBING
J 2
(-2475 4175);
DISPLAY 0.872340 (-2475 4175);
PAINT GREEN (-2475 4175);
DISPLAY INVISIBLE (-2475 4175);
FORCEPROP 2 LAST CDS_LIB mstr_standard
J 0
(-2475 4225);
PAINT MONO (-2475 4225);
DISPLAY INVISIBLE (-2475 4225);
FORCEPROP 1 LAST PATH I36
J 2
(-2473 4225);
DISPLAY 0.872340 (-2473 4225);
PAINT GREEN (-2473 4225);
DISPLAY INVISIBLE (-2473 4225);
FORCEADD TAP..6
R 2
(-2275 3425);
FORCEPROP 3 LASTPIN (-2325 3425) SIG_NAME P3E_CPU0_PE2_SS_RXP<14>
J 0
(-2315 3435);
DISPLAY 0.659574 (-2315 3435);
PAINT MONO (-2315 3435);
DISPLAY INVISIBLE (-2315 3435);
FORCEPROP 1 LASTPIN (-2325 3425) BN 14
J 2
(-2273 3433);
DISPLAY 0.680851 (-2273 3433);
PAINT GREEN (-2273 3433);
FORCEPROP 1 LAST HDL_TAP TRUE
J 2
(-2600 3300);
DISPLAY 0.872340 (-2600 3300);
PAINT ORANGE (-2600 3300);
DISPLAY INVISIBLE (-2600 3300);
FORCEPROP 1 LAST BODY_TYPE PLUMBING
J 2
(-2275 3375);
DISPLAY 0.872340 (-2275 3375);
PAINT GREEN (-2275 3375);
DISPLAY INVISIBLE (-2275 3375);
FORCEPROP 2 LAST CDS_LIB mstr_standard
J 0
(-2275 3425);
PAINT MONO (-2275 3425);
DISPLAY INVISIBLE (-2275 3425);
FORCEPROP 1 LAST PATH I37
J 2
(-2273 3425);
DISPLAY 0.872340 (-2273 3425);
PAINT GREEN (-2273 3425);
DISPLAY INVISIBLE (-2273 3425);
FORCEADD TAP..6
R 2
(-2275 3725);
FORCEPROP 3 LASTPIN (-2325 3725) SIG_NAME P3E_CPU0_PE2_SS_RXP<12>
J 0
(-2315 3735);
DISPLAY 0.659574 (-2315 3735);
PAINT MONO (-2315 3735);
DISPLAY INVISIBLE (-2315 3735);
FORCEPROP 1 LASTPIN (-2325 3725) BN 12
J 2
(-2273 3733);
DISPLAY 0.680851 (-2273 3733);
PAINT GREEN (-2273 3733);
FORCEPROP 1 LAST HDL_TAP TRUE
J 2
(-2600 3600);
DISPLAY 0.872340 (-2600 3600);
PAINT ORANGE (-2600 3600);
DISPLAY INVISIBLE (-2600 3600);
FORCEPROP 1 LAST BODY_TYPE PLUMBING
J 2
(-2275 3675);
DISPLAY 0.872340 (-2275 3675);
PAINT GREEN (-2275 3675);
DISPLAY INVISIBLE (-2275 3675);
FORCEPROP 2 LAST CDS_LIB mstr_standard
J 0
(-2275 3725);
PAINT MONO (-2275 3725);
DISPLAY INVISIBLE (-2275 3725);
FORCEPROP 1 LAST PATH I38
J 2
(-2273 3725);
DISPLAY 0.872340 (-2273 3725);
PAINT GREEN (-2273 3725);
DISPLAY INVISIBLE (-2273 3725);
FORCEADD TAP..6
R 2
(-2275 3625);
FORCEPROP 3 LASTPIN (-2325 3625) SIG_NAME P3E_CPU0_PE2_SS_RXP<13>
J 0
(-2315 3635);
DISPLAY 0.659574 (-2315 3635);
PAINT MONO (-2315 3635);
DISPLAY INVISIBLE (-2315 3635);
FORCEPROP 1 LASTPIN (-2325 3625) BN 13
J 2
(-2273 3633);
DISPLAY 0.680851 (-2273 3633);
PAINT GREEN (-2273 3633);
FORCEPROP 1 LAST HDL_TAP TRUE
J 2
(-2600 3500);
DISPLAY 0.872340 (-2600 3500);
PAINT ORANGE (-2600 3500);
DISPLAY INVISIBLE (-2600 3500);
FORCEPROP 1 LAST BODY_TYPE PLUMBING
J 2
(-2275 3575);
DISPLAY 0.872340 (-2275 3575);
PAINT GREEN (-2275 3575);
DISPLAY INVISIBLE (-2275 3575);
FORCEPROP 2 LAST CDS_LIB mstr_standard
J 0
(-2275 3625);
PAINT MONO (-2275 3625);
DISPLAY INVISIBLE (-2275 3625);
FORCEPROP 1 LAST PATH I39
J 2
(-2273 3625);
DISPLAY 0.872340 (-2273 3625);
PAINT GREEN (-2273 3625);
DISPLAY INVISIBLE (-2273 3625);
FORCEADD TAP..6
R 2
(-2275 4025);
FORCEPROP 3 LASTPIN (-2325 4025) SIG_NAME P3E_CPU0_PE2_SS_RXP<10>
J 0
(-2315 4035);
DISPLAY 0.659574 (-2315 4035);
PAINT MONO (-2315 4035);
DISPLAY INVISIBLE (-2315 4035);
FORCEPROP 1 LASTPIN (-2325 4025) BN 10
J 2
(-2273 4033);
DISPLAY 0.680851 (-2273 4033);
PAINT GREEN (-2273 4033);
FORCEPROP 1 LAST HDL_TAP TRUE
J 2
(-2600 3900);
DISPLAY 0.872340 (-2600 3900);
PAINT ORANGE (-2600 3900);
DISPLAY INVISIBLE (-2600 3900);
FORCEPROP 1 LAST BODY_TYPE PLUMBING
J 2
(-2275 3975);
DISPLAY 0.872340 (-2275 3975);
PAINT GREEN (-2275 3975);
DISPLAY INVISIBLE (-2275 3975);
FORCEPROP 2 LAST CDS_LIB mstr_standard
J 0
(-2275 4025);
PAINT MONO (-2275 4025);
DISPLAY INVISIBLE (-2275 4025);
FORCEPROP 1 LAST PATH I40
J 2
(-2273 4025);
DISPLAY 0.872340 (-2273 4025);
PAINT GREEN (-2273 4025);
DISPLAY INVISIBLE (-2273 4025);
FORCEADD TAP..6
R 2
(-2275 3875);
FORCEPROP 3 LASTPIN (-2325 3875) SIG_NAME P3E_CPU0_PE2_SS_RXP<11>
J 0
(-2315 3885);
DISPLAY 0.659574 (-2315 3885);
PAINT MONO (-2315 3885);
DISPLAY INVISIBLE (-2315 3885);
FORCEPROP 1 LASTPIN (-2325 3875) BN 11
J 2
(-2273 3883);
DISPLAY 0.680851 (-2273 3883);
PAINT GREEN (-2273 3883);
FORCEPROP 1 LAST HDL_TAP TRUE
J 2
(-2600 3750);
DISPLAY 0.872340 (-2600 3750);
PAINT ORANGE (-2600 3750);
DISPLAY INVISIBLE (-2600 3750);
FORCEPROP 1 LAST BODY_TYPE PLUMBING
J 2
(-2275 3825);
DISPLAY 0.872340 (-2275 3825);
PAINT GREEN (-2275 3825);
DISPLAY INVISIBLE (-2275 3825);
FORCEPROP 2 LAST CDS_LIB mstr_standard
J 0
(-2275 3875);
PAINT MONO (-2275 3875);
DISPLAY INVISIBLE (-2275 3875);
FORCEPROP 1 LAST PATH I41
J 2
(-2273 3875);
DISPLAY 0.872340 (-2273 3875);
PAINT GREEN (-2273 3875);
DISPLAY INVISIBLE (-2273 3875);
FORCEADD TAP..6
R 2
(-2275 4175);
FORCEPROP 3 LASTPIN (-2325 4175) SIG_NAME P3E_CPU0_PE2_SS_RXP<9>
J 0
(-2315 4185);
DISPLAY 0.659574 (-2315 4185);
PAINT MONO (-2315 4185);
DISPLAY INVISIBLE (-2315 4185);
FORCEPROP 1 LASTPIN (-2325 4175) BN 9
J 2
(-2273 4183);
DISPLAY 0.680851 (-2273 4183);
PAINT GREEN (-2273 4183);
FORCEPROP 1 LAST HDL_TAP TRUE
J 2
(-2600 4050);
DISPLAY 0.872340 (-2600 4050);
PAINT ORANGE (-2600 4050);
DISPLAY INVISIBLE (-2600 4050);
FORCEPROP 1 LAST BODY_TYPE PLUMBING
J 2
(-2275 4125);
DISPLAY 0.872340 (-2275 4125);
PAINT GREEN (-2275 4125);
DISPLAY INVISIBLE (-2275 4125);
FORCEPROP 2 LAST CDS_LIB mstr_standard
J 0
(-2275 4175);
PAINT MONO (-2275 4175);
DISPLAY INVISIBLE (-2275 4175);
FORCEPROP 1 LAST PATH I42
J 2
(-2273 4175);
DISPLAY 0.872340 (-2273 4175);
PAINT GREEN (-2273 4175);
DISPLAY INVISIBLE (-2273 4175);
FORCEADD TAP..6
R 2
(-2275 4325);
FORCEPROP 3 LASTPIN (-2325 4325) SIG_NAME P3E_CPU0_PE2_SS_RXP<8>
J 0
(-2315 4335);
DISPLAY 0.659574 (-2315 4335);
PAINT MONO (-2315 4335);
DISPLAY INVISIBLE (-2315 4335);
FORCEPROP 1 LASTPIN (-2325 4325) BN 8
J 2
(-2273 4333);
DISPLAY 0.680851 (-2273 4333);
PAINT GREEN (-2273 4333);
FORCEPROP 1 LAST HDL_TAP TRUE
J 2
(-2600 4200);
DISPLAY 0.872340 (-2600 4200);
PAINT ORANGE (-2600 4200);
DISPLAY INVISIBLE (-2600 4200);
FORCEPROP 1 LAST BODY_TYPE PLUMBING
J 2
(-2275 4275);
DISPLAY 0.872340 (-2275 4275);
PAINT GREEN (-2275 4275);
DISPLAY INVISIBLE (-2275 4275);
FORCEPROP 2 LAST CDS_LIB mstr_standard
J 0
(-2275 4325);
PAINT MONO (-2275 4325);
DISPLAY INVISIBLE (-2275 4325);
FORCEPROP 1 LAST PATH I43
J 2
(-2273 4325);
DISPLAY 0.872340 (-2273 4325);
PAINT GREEN (-2273 4325);
DISPLAY INVISIBLE (-2273 4325);
FORCEADD TAP..6
R 2
(-2475 4375);
FORCEPROP 3 LASTPIN (-2525 4375) SIG_NAME P3E_CPU0_PE2_SS_RXN<8>
J 0
(-2515 4385);
DISPLAY 0.659574 (-2515 4385);
PAINT MONO (-2515 4385);
DISPLAY INVISIBLE (-2515 4385);
FORCEPROP 1 LASTPIN (-2525 4375) BN 8
J 2
(-2473 4383);
DISPLAY 0.680851 (-2473 4383);
PAINT GREEN (-2473 4383);
FORCEPROP 1 LAST HDL_TAP TRUE
J 2
(-2800 4250);
DISPLAY 0.872340 (-2800 4250);
PAINT ORANGE (-2800 4250);
DISPLAY INVISIBLE (-2800 4250);
FORCEPROP 1 LAST BODY_TYPE PLUMBING
J 2
(-2475 4325);
DISPLAY 0.872340 (-2475 4325);
PAINT GREEN (-2475 4325);
DISPLAY INVISIBLE (-2475 4325);
FORCEPROP 2 LAST CDS_LIB mstr_standard
J 0
(-2475 4375);
PAINT MONO (-2475 4375);
DISPLAY INVISIBLE (-2475 4375);
FORCEPROP 1 LAST PATH I44
J 2
(-2473 4375);
DISPLAY 0.872340 (-2473 4375);
PAINT GREEN (-2473 4375);
DISPLAY INVISIBLE (-2473 4375);
FORCEADD OFFPAGE..2
(-1250 4600);
FORCEPROP 2 LAST $XR0 31 
J 0
(-1061 4600);
DISPLAY 0.638298 (-1061 4600);
PAINT MONO (-1061 4600);
FORCEPROP 1 LAST COMMENT_BODY TRUE
J 0
(-1295 4505);
DISPLAY 0.872340 (-1295 4505);
PAINT GREEN (-1295 4505);
DISPLAY INVISIBLE (-1295 4505);
FORCEPROP 1 LAST OFFPAGE TRUE
J 0
(-925 4475);
DISPLAY 0.872340 (-925 4475);
PAINT ORANGE (-925 4475);
DISPLAY INVISIBLE (-925 4475);
FORCEPROP 2 LAST CDS_LIB mstr_standard
J 0
(-1250 4600);
PAINT MONO (-1250 4600);
DISPLAY INVISIBLE (-1250 4600);
FORCEPROP 2 LAST PATH I45
J 0
(-950 4650);
DISPLAY 1.021277 (-950 4650);
PAINT ORANGE (-950 4650);
DISPLAY INVISIBLE (-950 4650);
FORCEADD OFFPAGE..2
(-1250 4475);
FORCEPROP 2 LAST $XR0 31 
J 0
(-1061 4475);
DISPLAY 0.638298 (-1061 4475);
PAINT MONO (-1061 4475);
FORCEPROP 1 LAST COMMENT_BODY TRUE
J 0
(-1295 4380);
DISPLAY 0.872340 (-1295 4380);
PAINT GREEN (-1295 4380);
DISPLAY INVISIBLE (-1295 4380);
FORCEPROP 1 LAST OFFPAGE TRUE
J 0
(-925 4350);
DISPLAY 0.872340 (-925 4350);
PAINT ORANGE (-925 4350);
DISPLAY INVISIBLE (-925 4350);
FORCEPROP 2 LAST CDS_LIB mstr_standard
J 0
(-1250 4475);
PAINT MONO (-1250 4475);
DISPLAY INVISIBLE (-1250 4475);
FORCEPROP 2 LAST PATH I46
J 0
(-925 4525);
DISPLAY 1.021277 (-925 4525);
PAINT ORANGE (-925 4525);
DISPLAY INVISIBLE (-925 4525);
FORCEADD SMC-CONN60A-22-GP..1
(-4000 3775);
FORCEPROP 0 LASTPIN (-3850 2975) $PN NP2
J 0
(-3840 2985);
DISPLAY 0.808511 (-3840 2985);
PAINT MONO (-3840 2985);
FORCEPROP 0 LASTPIN (-4250 3125) $PN 55
J 2
(-4260 3135);
DISPLAY 0.808511 (-4260 3135);
PAINT MONO (-4260 3135);
FORCEPROP 0 LASTPIN (-4250 3175) $PN 53
J 2
(-4260 3185);
DISPLAY 0.808511 (-4260 3185);
PAINT MONO (-4260 3185);
FORCEPROP 0 LASTPIN (-4250 2925) $PN PTH2
J 2
(-4260 2935);
DISPLAY 0.808511 (-4260 2935);
PAINT MONO (-4260 2935);
FORCEPROP 0 LASTPIN (-3750 3175) $PN 54
J 0
(-3740 3185);
DISPLAY 0.808511 (-3740 3185);
PAINT MONO (-3740 3185);
FORCEPROP 0 LASTPIN (-3750 3225) $PN 52
J 0
(-3740 3235);
DISPLAY 0.808511 (-3740 3235);
PAINT MONO (-3740 3235);
FORCEPROP 0 LASTPIN (-3750 3275) $PN 50
J 0
(-3740 3285);
DISPLAY 0.808511 (-3740 3285);
PAINT MONO (-3740 3285);
FORCEPROP 0 LASTPIN (-3750 3375) $PN 46
J 0
(-3740 3385);
DISPLAY 0.808511 (-3740 3385);
PAINT MONO (-3740 3385);
FORCEPROP 0 LASTPIN (-4250 3425) $PN 43
J 2
(-4260 3435);
DISPLAY 0.808511 (-4260 3435);
PAINT MONO (-4260 3435);
FORCEPROP 0 LASTPIN (-4250 3075) $PN 57
J 2
(-4260 3085);
DISPLAY 0.808511 (-4260 3085);
PAINT MONO (-4260 3085);
FORCEPROP 0 LASTPIN (-4250 3275) $PN 49
J 2
(-4260 3285);
DISPLAY 0.808511 (-4260 3285);
PAINT MONO (-4260 3285);
FORCEPROP 0 LASTPIN (-4250 3375) $PN 45
J 2
(-4260 3385);
DISPLAY 0.808511 (-4260 3385);
PAINT MONO (-4260 3385);
FORCEPROP 0 LASTPIN (-3750 3075) $PN 58
J 0
(-3740 3085);
DISPLAY 0.808511 (-3740 3085);
PAINT MONO (-3740 3085);
FORCEPROP 0 LASTPIN (-3750 3025) $PN 60
J 0
(-3740 3035);
DISPLAY 0.808511 (-3740 3035);
PAINT MONO (-3740 3035);
FORCEPROP 0 LASTPIN (-3750 3525) $PN 40
J 0
(-3740 3535);
DISPLAY 0.808511 (-3740 3535);
PAINT MONO (-3740 3535);
FORCEPROP 0 LASTPIN (-4250 4625) $PN PTH1
J 2
(-4260 4635);
DISPLAY 0.808511 (-4260 4635);
PAINT MONO (-4260 4635);
FORCEPROP 0 LASTPIN (-4250 3775) $PN 29
J 2
(-4260 3785);
DISPLAY 0.808511 (-4260 3785);
PAINT MONO (-4260 3785);
FORCEPROP 0 LASTPIN (-4250 3025) $PN 59
J 2
(-4260 3035);
DISPLAY 0.808511 (-4260 3035);
PAINT MONO (-4260 3035);
FORCEPROP 1 LAST LOCATION CONX8
J 0
(-4105 4705);
DISPLAY 0.617021 (-4105 4705);
PAINT GREEN (-4105 4705);
FORCEPROP 0 LASTPIN (-4250 4525) $PN 1
J 2
(-4260 4535);
DISPLAY 0.808511 (-4260 4535);
PAINT MONO (-4260 4535);
FORCEPROP 0 LASTPIN (-3750 4425) $PN 4
J 0
(-3740 4435);
DISPLAY 0.808511 (-3740 4435);
PAINT MONO (-3740 4435);
FORCEPROP 0 LASTPIN (-3750 3425) $PN 44
J 0
(-3740 3435);
DISPLAY 0.808511 (-3740 3435);
PAINT MONO (-3740 3435);
FORCEPROP 0 LASTPIN (-4250 3525) $PN 39
J 2
(-4260 3535);
DISPLAY 0.808511 (-4260 3535);
PAINT MONO (-4260 3535);
FORCEPROP 0 LASTPIN (-3750 3825) $PN 28
J 0
(-3740 3835);
DISPLAY 0.808511 (-3740 3835);
PAINT MONO (-3740 3835);
FORCEPROP 0 LASTPIN (-4250 3475) $PN 41
J 2
(-4260 3485);
DISPLAY 0.808511 (-4260 3485);
PAINT MONO (-4260 3485);
FORCEPROP 0 LASTPIN (-3750 3575) $PN 38
J 0
(-3740 3585);
DISPLAY 0.808511 (-3740 3585);
PAINT MONO (-3740 3585);
FORCEPROP 0 LASTPIN (-4250 4425) $PN 3
J 2
(-4260 4435);
DISPLAY 0.808511 (-4260 4435);
PAINT MONO (-4260 4435);
FORCEPROP 0 LASTPIN (-4250 4075) $PN 17
J 2
(-4260 4085);
DISPLAY 0.808511 (-4260 4085);
PAINT MONO (-4260 4085);
FORCEPROP 0 LASTPIN (-3750 3675) $PN 34
J 0
(-3740 3685);
DISPLAY 0.808511 (-3740 3685);
PAINT MONO (-3740 3685);
FORCEPROP 0 LASTPIN (-3750 3725) $PN 32
J 0
(-3740 3735);
DISPLAY 0.808511 (-3740 3735);
PAINT MONO (-3740 3735);
FORCEPROP 0 LASTPIN (-3750 4025) $PN 20
J 0
(-3740 4035);
DISPLAY 0.808511 (-3740 4035);
PAINT MONO (-3740 4035);
FORCEPROP 0 LASTPIN (-3750 4325) $PN 8
J 0
(-3740 4335);
DISPLAY 0.808511 (-3740 4335);
PAINT MONO (-3740 4335);
FORCEPROP 0 LASTPIN (-4250 3575) $PN 37
J 2
(-4260 3585);
DISPLAY 0.808511 (-4260 3585);
PAINT MONO (-4260 3585);
FORCEPROP 0 LASTPIN (-4250 3975) $PN 21
J 2
(-4260 3985);
DISPLAY 0.808511 (-4260 3985);
PAINT MONO (-4260 3985);
FORCEPROP 0 LASTPIN (-3750 3975) $PN 22
J 0
(-3740 3985);
DISPLAY 0.808511 (-3740 3985);
PAINT MONO (-3740 3985);
FORCEPROP 0 LASTPIN (-4250 4125) $PN 15
J 2
(-4260 4135);
DISPLAY 0.808511 (-4260 4135);
PAINT MONO (-4260 4135);
FORCEPROP 0 LASTPIN (-4250 4325) $PN 7
J 2
(-4260 4335);
DISPLAY 0.808511 (-4260 4335);
PAINT MONO (-4260 4335);
FORCEPROP 0 LASTPIN (-3750 4125) $PN 16
J 0
(-3740 4135);
DISPLAY 0.808511 (-3740 4135);
PAINT MONO (-3740 4135);
FORCEPROP 0 LASTPIN (-3750 3775) $PN 30
J 0
(-3740 3785);
DISPLAY 0.808511 (-3740 3785);
PAINT MONO (-3740 3785);
FORCEPROP 0 LASTPIN (-3750 3875) $PN 26
J 0
(-3740 3885);
DISPLAY 0.808511 (-3740 3885);
PAINT MONO (-3740 3885);
FORCEPROP 0 LASTPIN (-3750 3925) $PN 24
J 0
(-3740 3935);
DISPLAY 0.808511 (-3740 3935);
PAINT MONO (-3740 3935);
FORCEPROP 0 LASTPIN (-3750 4075) $PN 18
J 0
(-3740 4085);
DISPLAY 0.808511 (-3740 4085);
PAINT MONO (-3740 4085);
FORCEPROP 0 LASTPIN (-3750 4175) $PN 14
J 0
(-3740 4185);
DISPLAY 0.808511 (-3740 4185);
PAINT MONO (-3740 4185);
FORCEPROP 0 LASTPIN (-3750 4225) $PN 12
J 0
(-3740 4235);
DISPLAY 0.808511 (-3740 4235);
PAINT MONO (-3740 4235);
FORCEPROP 0 LASTPIN (-4250 3625) $PN 35
J 2
(-4260 3635);
DISPLAY 0.808511 (-4260 3635);
PAINT MONO (-4260 3635);
FORCEPROP 0 LASTPIN (-4250 3725) $PN 31
J 2
(-4260 3735);
DISPLAY 0.808511 (-4260 3735);
PAINT MONO (-4260 3735);
FORCEPROP 0 LASTPIN (-4250 3825) $PN 27
J 2
(-4260 3835);
DISPLAY 0.808511 (-4260 3835);
PAINT MONO (-4260 3835);
FORCEPROP 0 LASTPIN (-4250 3875) $PN 25
J 2
(-4260 3885);
DISPLAY 0.808511 (-4260 3885);
PAINT MONO (-4260 3885);
FORCEPROP 0 LASTPIN (-4250 3925) $PN 23
J 2
(-4260 3935);
DISPLAY 0.808511 (-4260 3935);
PAINT MONO (-4260 3935);
FORCEPROP 0 LASTPIN (-4250 4025) $PN 19
J 2
(-4260 4035);
DISPLAY 0.808511 (-4260 4035);
PAINT MONO (-4260 4035);
FORCEPROP 0 LASTPIN (-4250 4175) $PN 13
J 2
(-4260 4185);
DISPLAY 0.808511 (-4260 4185);
PAINT MONO (-4260 4185);
FORCEPROP 0 LASTPIN (-4250 4225) $PN 11
J 2
(-4260 4235);
DISPLAY 0.808511 (-4260 4235);
PAINT MONO (-4260 4235);
FORCEPROP 0 LASTPIN (-4250 4275) $PN 9
J 2
(-4260 4285);
DISPLAY 0.808511 (-4260 4285);
PAINT MONO (-4260 4285);
FORCEPROP 0 LASTPIN (-4250 4375) $PN 5
J 2
(-4260 4385);
DISPLAY 0.808511 (-4260 4385);
PAINT MONO (-4260 4385);
FORCEPROP 0 LASTPIN (-3750 4375) $PN 6
J 0
(-3740 4385);
DISPLAY 0.808511 (-3740 4385);
PAINT MONO (-3740 4385);
FORCEPROP 0 LASTPIN (-3750 4275) $PN 10
J 0
(-3740 4285);
DISPLAY 0.808511 (-3740 4285);
PAINT MONO (-3740 4285);
FORCEPROP 0 LASTPIN (-3750 4525) $PN 2
J 0
(-3740 4535);
DISPLAY 0.808511 (-3740 4535);
PAINT MONO (-3740 4535);
FORCEPROP 0 LASTPIN (-4150 4575) $PN NP1
J 2
(-4160 4585);
DISPLAY 0.808511 (-4160 4585);
PAINT MONO (-4160 4585);
FORCEPROP 0 LASTPIN (-4250 3675) $PN 33
J 2
(-4260 3685);
DISPLAY 0.808511 (-4260 3685);
PAINT MONO (-4260 3685);
FORCEPROP 0 LASTPIN (-3750 3475) $PN 42
J 0
(-3740 3485);
DISPLAY 0.808511 (-3740 3485);
PAINT MONO (-3740 3485);
FORCEPROP 0 LASTPIN (-3750 3625) $PN 36
J 0
(-3740 3635);
DISPLAY 0.808511 (-3740 3635);
PAINT MONO (-3740 3635);
FORCEPROP 0 LASTPIN (-3750 3125) $PN 56
J 0
(-3740 3135);
DISPLAY 0.808511 (-3740 3135);
PAINT MONO (-3740 3135);
FORCEPROP 1 LAST VALUE SMC-CONN60A-22-GP
J 0
(-4100 2825);
DISPLAY 0.617021 (-4100 2825);
PAINT GREEN (-4100 2825);
FORCEPROP 0 LASTPIN (-4250 3225) $PN 51
J 2
(-4260 3235);
DISPLAY 0.808511 (-4260 3235);
PAINT MONO (-4260 3235);
FORCEPROP 0 LASTPIN (-3750 3325) $PN 48
J 0
(-3740 3335);
DISPLAY 0.808511 (-3740 3335);
PAINT MONO (-3740 3335);
FORCEPROP 0 LASTPIN (-4250 3325) $PN 47
J 2
(-4260 3335);
DISPLAY 0.808511 (-4260 3335);
PAINT MONO (-4260 3335);
FORCEPROP 1 LAST PATH I48
J 0
(-4000 3775);
DISPLAY 0.617021 (-4000 3775);
PAINT GREEN (-4000 3775);
DISPLAY INVISIBLE (-4000 3775);
FORCEPROP 0 LAST CDS_SEC 1
J 0
(-4100 4750);
PAINT MONO (-4100 4750);
DISPLAY INVISIBLE (-4100 4750);
FORCEPROP 0 LAST $SEC 1
J 0
(-4100 4750);
PAINT MONO (-4100 4750);
DISPLAY INVISIBLE (-4100 4750);
FORCEPROP 0 LAST CDS_LOCATION CONX8
J 0
(-4100 4750);
PAINT MONO (-4100 4750);
DISPLAY INVISIBLE (-4100 4750);
FORCEPROP 1 LAST CDS_LMAN_SYM_OUTLINE -100,900,100,-900
J 0
(-4000 3775);
DISPLAY 0.468085 (-4000 3775);
PAINT GREEN (-4000 3775);
DISPLAY INVISIBLE (-4000 3775);
FORCEPROP 2 LAST CDS_LIB w_hdl
J 0
(-4000 3775);
PAINT MONO (-4000 3775);
DISPLAY INVISIBLE (-4000 3775);
FORCEPROP 1 LAST PART_NUMBER 020.C0082.0060
J 0
(-4000 3775);
DISPLAY 0.617021 (-4000 3775);
PAINT GREEN (-4000 3775);
DISPLAY INVISIBLE (-4000 3775);
FORCEPROP 1 LAST PACK_TYPE CONN-G7
J 0
(-4000 3775);
DISPLAY 0.617021 (-4000 3775);
PAINT GREEN (-4000 3775);
DISPLAY INVISIBLE (-4000 3775);
FORCEADD TAP..1
R 2
(-5275 3325);
FORCEPROP 3 LASTPIN (-5225 3325) SIG_NAME P3E_CPU0_PE2_SS_C_TXP<15>
J 0
(-5215 3335);
DISPLAY 0.659574 (-5215 3335);
PAINT MONO (-5215 3335);
DISPLAY INVISIBLE (-5215 3335);
FORCEPROP 1 LASTPIN (-5225 3325) BN 15
J 2
(-5213 3333);
DISPLAY 0.680851 (-5213 3333);
PAINT GREEN (-5213 3333);
FORCEPROP 1 LAST HDL_TAP TRUE
J 2
(-5600 3200);
DISPLAY 0.872340 (-5600 3200);
PAINT ORANGE (-5600 3200);
DISPLAY INVISIBLE (-5600 3200);
FORCEPROP 1 LAST BODY_TYPE PLUMBING
J 2
(-5275 3375);
DISPLAY 0.872340 (-5275 3375);
PAINT GREEN (-5275 3375);
DISPLAY INVISIBLE (-5275 3375);
FORCEPROP 2 LAST CDS_LIB mstr_standard
J 0
(-5275 3325);
PAINT MONO (-5275 3325);
DISPLAY INVISIBLE (-5275 3325);
FORCEPROP 1 LAST PATH I5
J 2
(-5273 3325);
DISPLAY 0.872340 (-5273 3325);
PAINT GREEN (-5273 3325);
DISPLAY INVISIBLE (-5273 3325);
FORCEADD TAP..1
R 2
(-5900 4425);
FORCEPROP 3 LASTPIN (-5850 4425) SIG_NAME P3E_CPU0_PE2_SS_C_TXN<8>
J 0
(-5840 4435);
DISPLAY 0.659574 (-5840 4435);
PAINT MONO (-5840 4435);
DISPLAY INVISIBLE (-5840 4435);
FORCEPROP 1 LASTPIN (-5850 4425) BN 8
J 2
(-5838 4433);
DISPLAY 0.680851 (-5838 4433);
PAINT GREEN (-5838 4433);
FORCEPROP 1 LAST HDL_TAP TRUE
J 2
(-6225 4300);
DISPLAY 0.872340 (-6225 4300);
PAINT ORANGE (-6225 4300);
DISPLAY INVISIBLE (-6225 4300);
FORCEPROP 1 LAST BODY_TYPE PLUMBING
J 2
(-5900 4475);
DISPLAY 0.872340 (-5900 4475);
PAINT GREEN (-5900 4475);
DISPLAY INVISIBLE (-5900 4475);
FORCEPROP 2 LAST CDS_LIB mstr_standard
J 0
(-5900 4425);
PAINT MONO (-5900 4425);
DISPLAY INVISIBLE (-5900 4425);
FORCEPROP 1 LAST PATH I52
J 2
(-5898 4425);
DISPLAY 0.872340 (-5898 4425);
PAINT GREEN (-5898 4425);
DISPLAY INVISIBLE (-5898 4425);
FORCEADD TAP..1
R 2
(-5275 4375);
FORCEPROP 3 LASTPIN (-5225 4375) SIG_NAME P3E_CPU0_PE2_SS_C_TXP<8>
J 0
(-5215 4385);
DISPLAY 0.659574 (-5215 4385);
PAINT MONO (-5215 4385);
DISPLAY INVISIBLE (-5215 4385);
FORCEPROP 1 LASTPIN (-5225 4375) BN 8
J 2
(-5213 4383);
DISPLAY 0.680851 (-5213 4383);
PAINT GREEN (-5213 4383);
FORCEPROP 1 LAST HDL_TAP TRUE
J 2
(-5600 4250);
DISPLAY 0.872340 (-5600 4250);
PAINT ORANGE (-5600 4250);
DISPLAY INVISIBLE (-5600 4250);
FORCEPROP 1 LAST BODY_TYPE PLUMBING
J 2
(-5275 4425);
DISPLAY 0.872340 (-5275 4425);
PAINT GREEN (-5275 4425);
DISPLAY INVISIBLE (-5275 4425);
FORCEPROP 2 LAST CDS_LIB mstr_standard
J 0
(-5275 4375);
PAINT MONO (-5275 4375);
DISPLAY INVISIBLE (-5275 4375);
FORCEPROP 1 LAST PATH I53
J 2
(-5273 4375);
DISPLAY 0.872340 (-5273 4375);
PAINT GREEN (-5273 4375);
DISPLAY INVISIBLE (-5273 4375);
FORCEADD OFFPAGE..3
R 2
(-5475 3025);
FORCEPROP 2 LAST $XR0 115 
J 0
(-5755 3025);
DISPLAY 0.638298 (-5755 3025);
PAINT MONO (-5755 3025);
FORCEPROP 2 LAST PATH I54
J 0
(-5750 3075);
DISPLAY 1.021277 (-5750 3075);
PAINT ORANGE (-5750 3075);
DISPLAY INVISIBLE (-5750 3075);
FORCEPROP 1 LAST COMMENT_BODY TRUE
J 2
(-5425 2925);
DISPLAY 1.170213 (-5425 2925);
PAINT GREEN (-5425 2925);
DISPLAY INVISIBLE (-5425 2925);
FORCEPROP 1 LAST OFFPAGE TRUE
J 2
(-5800 2900);
PAINT GREEN (-5800 2900);
DISPLAY INVISIBLE (-5800 2900);
FORCEPROP 2 LAST CDS_LIB mstr_standard
J 0
(-5475 3025);
PAINT MONO (-5475 3025);
DISPLAY INVISIBLE (-5475 3025);
FORCEPROP 2 LAST ROOM BMC
J 2
(-5950 3075);
PAINT MONO (-5950 3075);
DISPLAY INVISIBLE (-5950 3075);
FORCEPROP 2 LAST BOM_COST SM_CONTROLLER
J 2
(-5950 3075);
PAINT MONO (-5950 3075);
DISPLAY INVISIBLE (-5950 3075);
FORCEADD OFFPAGE..3
R 2
(-5475 3075);
FORCEPROP 2 LAST $XR0 115 
J 0
(-5755 3075);
DISPLAY 0.638298 (-5755 3075);
PAINT MONO (-5755 3075);
FORCEPROP 1 LAST COMMENT_BODY TRUE
J 2
(-5425 2975);
DISPLAY 1.170213 (-5425 2975);
PAINT GREEN (-5425 2975);
DISPLAY INVISIBLE (-5425 2975);
FORCEPROP 1 LAST OFFPAGE TRUE
J 2
(-5800 2950);
PAINT GREEN (-5800 2950);
DISPLAY INVISIBLE (-5800 2950);
FORCEPROP 2 LAST CDS_LIB mstr_standard
J 0
(-5475 3075);
PAINT MONO (-5475 3075);
DISPLAY INVISIBLE (-5475 3075);
FORCEPROP 2 LAST BOM_COST SM_CONTROLLER
J 2
(-5950 3125);
PAINT MONO (-5950 3125);
DISPLAY INVISIBLE (-5950 3125);
FORCEPROP 2 LAST ROOM BMC
J 2
(-5950 3125);
PAINT MONO (-5950 3125);
DISPLAY INVISIBLE (-5950 3125);
FORCEPROP 2 LAST PATH I55
J 0
(-5750 3125);
DISPLAY 1.021277 (-5750 3125);
PAINT ORANGE (-5750 3125);
DISPLAY INVISIBLE (-5750 3125);
FORCEADD RES..1
(-2700 3175);
FORCEPROP 1 LAST TOLERANCE 5%
J 0
(-2300 3175);
DISPLAY 0.617021 (-2300 3175);
PAINT SKYBLUE (-2300 3175);
FORCEPROP 1 LAST PACK_TYPE 0402
J 0
(-1675 3175);
DISPLAY 0.617021 (-1675 3175);
PAINT SKYBLUE (-1675 3175);
FORCEPROP 1 LAST WATTAGE 1/16W
J 0
(-2200 3175);
DISPLAY 0.617021 (-2200 3175);
PAINT SKYBLUE (-2200 3175);
FORCEPROP 1 LAST MATERIAL CHIP
J 0
(-2050 3175);
DISPLAY 0.617021 (-2050 3175);
PAINT SKYBLUE (-2050 3175);
FORCEPROP 1 LAST PART_NUMBER G21497-005
J 0
(-1925 3175);
DISPLAY 0.617021 (-1925 3175);
PAINT BLUE (-1925 3175);
FORCEPROP 1 LAST VALUE 0.0
J 0
(-2400 3175);
DISPLAY 0.617021 (-2400 3175);
PAINT SKYBLUE (-2400 3175);
FORCEPROP 1 LASTPIN (-2600 3175) $PN 2
J 0
(-2638 3187);
DISPLAY 0.617021 (-2638 3187);
PAINT ORANGE (-2638 3187);
FORCEPROP 1 LASTPIN (-2800 3175) $PN 1
J 0
(-2788 3187);
DISPLAY 0.617021 (-2788 3187);
PAINT ORANGE (-2788 3187);
FORCEPROP 1 LAST LOCATION R8W10
J 0
(-2550 3175);
DISPLAY 0.617021 (-2550 3175);
PAINT AQUA (-2550 3175);
FORCEPROP 1 LAST PATH I56
J 0
(-2750 3325);
DISPLAY 0.978723 (-2750 3325);
PAINT WHITE (-2750 3325);
DISPLAY INVISIBLE (-2750 3325);
FORCEPROP 2 LAST SEC 1
J 0
(-2750 3375);
DISPLAY 0.680851 (-2750 3375);
PAINT MONO (-2750 3375);
DISPLAY INVISIBLE (-2750 3375);
FORCEPROP 2 LAST SEC_TYPE 0402
J 0
(-2750 3375);
DISPLAY 1.021277 (-2750 3375);
PAINT ORANGE (-2750 3375);
DISPLAY INVISIBLE (-2750 3375);
FORCEPROP 2 LAST ROOM BMC_DEBUG_HEADER
J 0
(-2750 3275);
DISPLAY 1.021277 (-2750 3275);
PAINT ORANGE (-2750 3275);
DISPLAY INVISIBLE (-2750 3275);
FORCEPROP 2 LAST BOM_COST DEBUG
J 0
(-2750 3325);
DISPLAY 1.021277 (-2750 3325);
PAINT ORANGE (-2750 3325);
DISPLAY INVISIBLE (-2750 3325);
FORCEPROP 2 LAST CDS_LIB mstr_discrete
J 0
(-2700 3175);
PAINT ORANGE (-2700 3175);
DISPLAY INVISIBLE (-2700 3175);
FORCEPROP 2 LAST CDS_LOCATION R8W10
J 0
(-2750 3225);
DISPLAY 0.617021 (-2750 3225);
PAINT AQUA (-2750 3225);
DISPLAY INVISIBLE (-2750 3225);
FORCEADD RES..1
(-2700 3125);
FORCEPROP 1 LAST VALUE 0.0
J 0
(-2400 3125);
DISPLAY 0.617021 (-2400 3125);
PAINT SKYBLUE (-2400 3125);
FORCEPROP 1 LAST PACK_TYPE 0402
J 0
(-1675 3125);
DISPLAY 0.617021 (-1675 3125);
PAINT SKYBLUE (-1675 3125);
FORCEPROP 1 LAST PART_NUMBER G21497-005
J 0
(-1925 3125);
DISPLAY 0.617021 (-1925 3125);
PAINT BLUE (-1925 3125);
FORCEPROP 1 LASTPIN (-2600 3125) $PN 2
J 0
(-2638 3137);
DISPLAY 0.617021 (-2638 3137);
PAINT ORANGE (-2638 3137);
FORCEPROP 1 LAST MATERIAL CHIP
J 0
(-2050 3125);
DISPLAY 0.617021 (-2050 3125);
PAINT SKYBLUE (-2050 3125);
FORCEPROP 1 LAST WATTAGE 1/16W
J 0
(-2200 3125);
DISPLAY 0.617021 (-2200 3125);
PAINT SKYBLUE (-2200 3125);
FORCEPROP 1 LAST TOLERANCE 5%
J 0
(-2300 3125);
DISPLAY 0.617021 (-2300 3125);
PAINT SKYBLUE (-2300 3125);
FORCEPROP 1 LASTPIN (-2800 3125) $PN 1
J 0
(-2788 3137);
DISPLAY 0.617021 (-2788 3137);
PAINT ORANGE (-2788 3137);
FORCEPROP 1 LAST LOCATION R8W11
J 0
(-2550 3125);
DISPLAY 0.617021 (-2550 3125);
PAINT AQUA (-2550 3125);
FORCEPROP 2 LAST CDS_LIB mstr_discrete
J 0
(-2700 3125);
PAINT ORANGE (-2700 3125);
DISPLAY INVISIBLE (-2700 3125);
FORCEPROP 2 LAST BOM_COST DEBUG
J 0
(-2750 3275);
DISPLAY 1.021277 (-2750 3275);
PAINT ORANGE (-2750 3275);
DISPLAY INVISIBLE (-2750 3275);
FORCEPROP 2 LAST ROOM BMC_DEBUG_HEADER
J 0
(-2750 3225);
DISPLAY 1.021277 (-2750 3225);
PAINT ORANGE (-2750 3225);
DISPLAY INVISIBLE (-2750 3225);
FORCEPROP 2 LAST SEC_TYPE 0402
J 0
(-2750 3325);
DISPLAY 1.021277 (-2750 3325);
PAINT ORANGE (-2750 3325);
DISPLAY INVISIBLE (-2750 3325);
FORCEPROP 2 LAST SEC 1
J 0
(-2750 3325);
DISPLAY 0.680851 (-2750 3325);
PAINT MONO (-2750 3325);
DISPLAY INVISIBLE (-2750 3325);
FORCEPROP 1 LAST PATH I57
J 0
(-2750 3275);
DISPLAY 0.978723 (-2750 3275);
PAINT WHITE (-2750 3275);
DISPLAY INVISIBLE (-2750 3275);
FORCEPROP 2 LAST CDS_LOCATION R8W11
J 0
(-2750 3175);
DISPLAY 0.617021 (-2750 3175);
PAINT AQUA (-2750 3175);
DISPLAY INVISIBLE (-2750 3175);
FORCEADD RES..1
(-2700 3025);
FORCEPROP 1 LAST LOCATION R8W12
J 0
(-2550 3025);
DISPLAY 0.617021 (-2550 3025);
PAINT AQUA (-2550 3025);
FORCEPROP 1 LAST PART_NUMBER G21497-005
J 0
(-1925 3025);
DISPLAY 0.617021 (-1925 3025);
PAINT BLUE (-1925 3025);
FORCEPROP 1 LAST MATERIAL CHIP
J 0
(-2050 3025);
DISPLAY 0.617021 (-2050 3025);
PAINT SKYBLUE (-2050 3025);
FORCEPROP 1 LAST VALUE 0.0
J 0
(-2400 3025);
DISPLAY 0.617021 (-2400 3025);
PAINT SKYBLUE (-2400 3025);
FORCEPROP 1 LAST WATTAGE 1/16W
J 0
(-2200 3025);
DISPLAY 0.617021 (-2200 3025);
PAINT SKYBLUE (-2200 3025);
FORCEPROP 1 LAST PACK_TYPE 0402
J 0
(-1675 3025);
DISPLAY 0.617021 (-1675 3025);
PAINT SKYBLUE (-1675 3025);
FORCEPROP 1 LAST TOLERANCE 5%
J 0
(-2300 3025);
DISPLAY 0.617021 (-2300 3025);
PAINT SKYBLUE (-2300 3025);
FORCEPROP 1 LASTPIN (-2800 3025) $PN 1
J 0
(-2788 3037);
DISPLAY 0.617021 (-2788 3037);
PAINT ORANGE (-2788 3037);
FORCEPROP 1 LASTPIN (-2600 3025) $PN 2
J 0
(-2638 3037);
DISPLAY 0.617021 (-2638 3037);
PAINT ORANGE (-2638 3037);
FORCEPROP 1 LAST PATH I58
J 0
(-2750 3175);
DISPLAY 0.978723 (-2750 3175);
PAINT WHITE (-2750 3175);
DISPLAY INVISIBLE (-2750 3175);
FORCEPROP 2 LAST SEC 1
J 0
(-2750 3225);
DISPLAY 0.680851 (-2750 3225);
PAINT MONO (-2750 3225);
DISPLAY INVISIBLE (-2750 3225);
FORCEPROP 2 LAST SEC_TYPE 0402
J 0
(-2750 3225);
DISPLAY 1.021277 (-2750 3225);
PAINT ORANGE (-2750 3225);
DISPLAY INVISIBLE (-2750 3225);
FORCEPROP 2 LAST ROOM BMC_DEBUG_HEADER
J 0
(-2750 3125);
DISPLAY 1.021277 (-2750 3125);
PAINT ORANGE (-2750 3125);
DISPLAY INVISIBLE (-2750 3125);
FORCEPROP 2 LAST BOM_COST DEBUG
J 0
(-2750 3175);
DISPLAY 1.021277 (-2750 3175);
PAINT ORANGE (-2750 3175);
DISPLAY INVISIBLE (-2750 3175);
FORCEPROP 2 LAST CDS_LIB mstr_discrete
J 0
(-2700 3025);
PAINT ORANGE (-2700 3025);
DISPLAY INVISIBLE (-2700 3025);
FORCEPROP 2 LAST CDS_LOCATION R8W12
J 0
(-2750 3075);
DISPLAY 0.617021 (-2750 3075);
PAINT AQUA (-2750 3075);
DISPLAY INVISIBLE (-2750 3075);
FORCEADD RES..1
(-6500 3225);
FORCEPROP 1 LAST VALUE 0.0
J 0
(-6200 3225);
DISPLAY 0.617021 (-6200 3225);
PAINT SKYBLUE (-6200 3225);
FORCEPROP 1 LAST LOCATION R8W13
J 0
(-6350 3225);
DISPLAY 0.617021 (-6350 3225);
PAINT AQUA (-6350 3225);
FORCEPROP 1 LASTPIN (-6600 3225) $PN 1
J 0
(-6588 3237);
DISPLAY 0.617021 (-6588 3237);
PAINT ORANGE (-6588 3237);
FORCEPROP 1 LASTPIN (-6400 3225) $PN 2
J 0
(-6438 3237);
DISPLAY 0.617021 (-6438 3237);
PAINT ORANGE (-6438 3237);
FORCEPROP 1 LAST PACK_TYPE 0402
J 0
(-5475 3225);
DISPLAY 0.617021 (-5475 3225);
PAINT SKYBLUE (-5475 3225);
FORCEPROP 1 LAST MATERIAL CHIP
J 0
(-5850 3225);
DISPLAY 0.617021 (-5850 3225);
PAINT SKYBLUE (-5850 3225);
FORCEPROP 1 LAST WATTAGE 1/16W
J 0
(-6000 3225);
DISPLAY 0.617021 (-6000 3225);
PAINT SKYBLUE (-6000 3225);
FORCEPROP 1 LAST TOLERANCE 5%
J 0
(-6100 3225);
DISPLAY 0.617021 (-6100 3225);
PAINT SKYBLUE (-6100 3225);
FORCEPROP 1 LAST PART_NUMBER G21497-005
J 0
(-5725 3225);
DISPLAY 0.617021 (-5725 3225);
PAINT BLUE (-5725 3225);
FORCEPROP 1 LAST PATH I59
J 0
(-6550 3375);
DISPLAY 0.978723 (-6550 3375);
PAINT WHITE (-6550 3375);
DISPLAY INVISIBLE (-6550 3375);
FORCEPROP 2 LAST CDS_LIB mstr_discrete
J 0
(-6500 3225);
PAINT ORANGE (-6500 3225);
DISPLAY INVISIBLE (-6500 3225);
FORCEPROP 2 LAST BOM_COST DEBUG
J 0
(-6550 3375);
DISPLAY 1.021277 (-6550 3375);
PAINT ORANGE (-6550 3375);
DISPLAY INVISIBLE (-6550 3375);
FORCEPROP 2 LAST ROOM BMC_DEBUG_HEADER
J 0
(-6550 3325);
DISPLAY 1.021277 (-6550 3325);
PAINT ORANGE (-6550 3325);
DISPLAY INVISIBLE (-6550 3325);
FORCEPROP 2 LAST SEC_TYPE 0402
J 0
(-6550 3425);
DISPLAY 1.021277 (-6550 3425);
PAINT ORANGE (-6550 3425);
DISPLAY INVISIBLE (-6550 3425);
FORCEPROP 2 LAST SEC 1
J 0
(-6550 3425);
DISPLAY 0.680851 (-6550 3425);
PAINT MONO (-6550 3425);
DISPLAY INVISIBLE (-6550 3425);
FORCEPROP 2 LAST CDS_LOCATION R8W13
J 0
(-6550 3275);
DISPLAY 0.617021 (-6550 3275);
PAINT AQUA (-6550 3275);
DISPLAY INVISIBLE (-6550 3275);
FORCEADD TAP..1
R 2
(-5900 3375);
FORCEPROP 3 LASTPIN (-5850 3375) SIG_NAME P3E_CPU0_PE2_SS_C_TXN<15>
J 0
(-5840 3385);
DISPLAY 0.659574 (-5840 3385);
PAINT MONO (-5840 3385);
DISPLAY INVISIBLE (-5840 3385);
FORCEPROP 1 LASTPIN (-5850 3375) BN 15
J 2
(-5838 3383);
DISPLAY 0.680851 (-5838 3383);
PAINT GREEN (-5838 3383);
FORCEPROP 1 LAST HDL_TAP TRUE
J 2
(-6225 3250);
DISPLAY 0.872340 (-6225 3250);
PAINT ORANGE (-6225 3250);
DISPLAY INVISIBLE (-6225 3250);
FORCEPROP 1 LAST BODY_TYPE PLUMBING
J 2
(-5900 3425);
DISPLAY 0.872340 (-5900 3425);
PAINT GREEN (-5900 3425);
DISPLAY INVISIBLE (-5900 3425);
FORCEPROP 2 LAST CDS_LIB mstr_standard
J 0
(-5900 3375);
PAINT MONO (-5900 3375);
DISPLAY INVISIBLE (-5900 3375);
FORCEPROP 1 LAST PATH I6
J 2
(-5898 3375);
DISPLAY 0.872340 (-5898 3375);
PAINT GREEN (-5898 3375);
DISPLAY INVISIBLE (-5898 3375);
FORCEADD RES..1
(-6500 3175);
FORCEPROP 1 LAST PACK_TYPE 0402
J 0
(-5475 3175);
DISPLAY 0.617021 (-5475 3175);
PAINT SKYBLUE (-5475 3175);
FORCEPROP 1 LAST VALUE 0.0
J 0
(-6200 3175);
DISPLAY 0.617021 (-6200 3175);
PAINT SKYBLUE (-6200 3175);
FORCEPROP 1 LAST LOCATION R8W14
J 0
(-6350 3175);
DISPLAY 0.617021 (-6350 3175);
PAINT AQUA (-6350 3175);
FORCEPROP 1 LASTPIN (-6400 3175) $PN 2
J 0
(-6438 3187);
DISPLAY 0.617021 (-6438 3187);
PAINT ORANGE (-6438 3187);
FORCEPROP 1 LASTPIN (-6600 3175) $PN 1
J 0
(-6588 3187);
DISPLAY 0.617021 (-6588 3187);
PAINT ORANGE (-6588 3187);
FORCEPROP 1 LAST MATERIAL CHIP
J 0
(-5850 3175);
DISPLAY 0.617021 (-5850 3175);
PAINT SKYBLUE (-5850 3175);
FORCEPROP 1 LAST WATTAGE 1/16W
J 0
(-6000 3175);
DISPLAY 0.617021 (-6000 3175);
PAINT SKYBLUE (-6000 3175);
FORCEPROP 1 LAST TOLERANCE 5%
J 0
(-6100 3175);
DISPLAY 0.617021 (-6100 3175);
PAINT SKYBLUE (-6100 3175);
FORCEPROP 1 LAST PART_NUMBER G21497-005
J 0
(-5725 3175);
DISPLAY 0.617021 (-5725 3175);
PAINT BLUE (-5725 3175);
FORCEPROP 2 LAST SEC 1
J 0
(-6550 3375);
DISPLAY 0.680851 (-6550 3375);
PAINT MONO (-6550 3375);
DISPLAY INVISIBLE (-6550 3375);
FORCEPROP 2 LAST SEC_TYPE 0402
J 0
(-6550 3375);
DISPLAY 1.021277 (-6550 3375);
PAINT ORANGE (-6550 3375);
DISPLAY INVISIBLE (-6550 3375);
FORCEPROP 2 LAST ROOM BMC_DEBUG_HEADER
J 0
(-6550 3275);
DISPLAY 1.021277 (-6550 3275);
PAINT ORANGE (-6550 3275);
DISPLAY INVISIBLE (-6550 3275);
FORCEPROP 2 LAST BOM_COST DEBUG
J 0
(-6550 3325);
DISPLAY 1.021277 (-6550 3325);
PAINT ORANGE (-6550 3325);
DISPLAY INVISIBLE (-6550 3325);
FORCEPROP 2 LAST CDS_LIB mstr_discrete
J 0
(-6500 3175);
PAINT ORANGE (-6500 3175);
DISPLAY INVISIBLE (-6500 3175);
FORCEPROP 1 LAST PATH I60
J 0
(-6550 3325);
DISPLAY 0.978723 (-6550 3325);
PAINT WHITE (-6550 3325);
DISPLAY INVISIBLE (-6550 3325);
FORCEPROP 2 LAST CDS_LOCATION R8W14
J 0
(-6550 3225);
DISPLAY 0.617021 (-6550 3225);
PAINT AQUA (-6550 3225);
DISPLAY INVISIBLE (-6550 3225);
FORCEADD OFFPAGE..4
(-1050 3025);
FORCEPROP 2 LAST $XR2 254 
J 0
(-624 3025);
DISPLAY 0.638298 (-624 3025);
PAINT MONO (-624 3025);
FORCEPROP 2 LAST $XR1 189 
J 0
(-744 3025);
DISPLAY 0.638298 (-744 3025);
PAINT MONO (-744 3025);
FORCEPROP 2 LAST $XR0 144 
J 0
(-864 3025);
DISPLAY 0.638298 (-864 3025);
PAINT MONO (-864 3025);
FORCEPROP 1 LAST COMMENT_BODY TRUE
J 0
(-1075 2925);
DISPLAY 0.872340 (-1075 2925);
PAINT GREEN (-1075 2925);
DISPLAY INVISIBLE (-1075 2925);
FORCEPROP 1 LAST OFFPAGE TRUE
J 0
(-725 2900);
DISPLAY 0.872340 (-725 2900);
PAINT GREEN (-725 2900);
DISPLAY INVISIBLE (-725 2900);
FORCEPROP 2 LAST CDS_LIB mstr_standard
J 0
(-1050 3025);
PAINT MONO (-1050 3025);
DISPLAY INVISIBLE (-1050 3025);
FORCEPROP 2 LAST PATH I61
J 0
(-850 3075);
DISPLAY 1.021277 (-850 3075);
PAINT ORANGE (-850 3075);
DISPLAY INVISIBLE (-850 3075);
FORCEADD 74CBTLV1G125..1
(-3900 2000);
FORCEPROP 1 LAST PART_NUMBER C88177-001
J 0
(-4065 1860);
DISPLAY 0.617021 (-4065 1860);
PAINT BLUE (-4065 1860);
FORCEPROP 1 LAST POWER_GROUP VCC=P3V3_STBY;GND=GND;
J 0
(-4125 1800);
DISPLAY 0.617021 (-4125 1800);
PAINT ORANGE (-4125 1800);
FORCEPROP 1 LAST LOCATION U8W1
J 0
(-4066 2131);
DISPLAY 0.617021 (-4066 2131);
PAINT AQUA (-4066 2131);
FORCEPROP 1 LAST MATERIAL IC
J 0
(-4075 2220);
DISPLAY 0.617021 (-4075 2220);
PAINT SKYBLUE (-4075 2220);
FORCEPROP 2 LASTPIN (-4150 1950) $PN 1
J 2
(-4160 1960);
DISPLAY 0.617021 (-4160 1960);
PAINT ORANGE (-4160 1960);
FORCEPROP 2 LASTPIN (-4150 2000) $PN 2
J 2
(-4160 2010);
DISPLAY 0.617021 (-4160 2010);
PAINT ORANGE (-4160 2010);
FORCEPROP 2 LASTPIN (-3650 2000) $PN 4
J 0
(-3640 2010);
DISPLAY 0.617021 (-3640 2010);
PAINT ORANGE (-3640 2010);
FORCEPROP 1 LAST PACK_TYPE SMLF
J 0
(-4075 2170);
DISPLAY 0.617021 (-4075 2170);
PAINT SKYBLUE (-4075 2170);
FORCEPROP 1 LAST PATH I64
J 0
(-3800 2120);
DISPLAY 0.872340 (-3800 2120);
PAINT PINK (-3800 2120);
DISPLAY INVISIBLE (-3800 2120);
FORCEPROP 2 LAST SEC_TYPE SMLF
J 0
(-4075 2275);
DISPLAY 1.021277 (-4075 2275);
PAINT ORANGE (-4075 2275);
DISPLAY INVISIBLE (-4075 2275);
FORCEPROP 2 LAST CDS_LIB mstr_ttl
J 0
(-3900 2000);
PAINT ORANGE (-3900 2000);
DISPLAY INVISIBLE (-3900 2000);
FORCEPROP 0 LAST BOM_COST DEBUG
J 0
(-4075 2325);
DISPLAY 1.021277 (-4075 2325);
PAINT ORANGE (-4075 2325);
DISPLAY INVISIBLE (-4075 2325);
FORCEPROP 2 LAST SEC 1
J 0
(-4075 2275);
DISPLAY 0.680851 (-4075 2275);
PAINT MONO (-4075 2275);
DISPLAY INVISIBLE (-4075 2275);
FORCEPROP 0 LAST ROOM DEBUG
J 0
(-4075 2325);
DISPLAY 1.021277 (-4075 2325);
PAINT ORANGE (-4075 2325);
DISPLAY INVISIBLE (-4075 2325);
FORCEADD NC7SB3157..1
R 2
(-5950 1500);
FORCEPROP 1 LAST PART_NUMBER C99406-001
J 2
(-5650 1725);
DISPLAY 0.617021 (-5650 1725);
PAINT BLUE (-5650 1725);
FORCEPROP 2 LASTPIN (-5600 1350) $PN 5
J 0
(-5590 1360);
DISPLAY 0.617021 (-5590 1360);
PAINT WHITE (-5590 1360);
FORCEPROP 1 LAST MATERIAL IC
J 2
(-5650 1250);
DISPLAY 0.617021 (-5650 1250);
PAINT SKYBLUE (-5650 1250);
FORCEPROP 1 LAST PACK_TYPE SMLF
J 2
(-5775 1250);
DISPLAY 0.617021 (-5775 1250);
PAINT SKYBLUE (-5775 1250);
FORCEPROP 2 LASTPIN (-6300 1350) $PN 2
J 2
(-6310 1360);
DISPLAY 0.617021 (-6310 1360);
PAINT WHITE (-6310 1360);
FORCEPROP 2 LASTPIN (-5600 1450) $PN 1
J 0
(-5590 1460);
DISPLAY 0.617021 (-5590 1460);
PAINT WHITE (-5590 1460);
FORCEPROP 1 LAST LOCATION U8W2
J 2
(-5650 1775);
DISPLAY 0.617021 (-5650 1775);
PAINT AQUA (-5650 1775);
FORCEPROP 2 LASTPIN (-5600 1650) $PN 6
J 0
(-5590 1660);
DISPLAY 0.617021 (-5590 1660);
PAINT WHITE (-5590 1660);
FORCEPROP 2 LASTPIN (-6300 1500) $PN 4
J 2
(-6310 1510);
DISPLAY 0.617021 (-6310 1510);
PAINT WHITE (-6310 1510);
FORCEPROP 2 LASTPIN (-5600 1550) $PN 3
J 0
(-5590 1560);
DISPLAY 0.617021 (-5590 1560);
PAINT WHITE (-5590 1560);
FORCEPROP 1 LAST PATH I66
J 2
(-6025 1250);
DISPLAY 0.851064 (-6025 1250);
PAINT WHITE (-6025 1250);
DISPLAY INVISIBLE (-6025 1250);
FORCEPROP 2 LAST BOM_COST DEBUG
J 0
(-5650 1875);
DISPLAY 1.617021 (-5650 1875);
PAINT WHITE (-5650 1875);
DISPLAY INVISIBLE (-5650 1875);
FORCEPROP 2 LAST CDS_LIB mstr_analog
J 2
(-5950 1500);
DISPLAY 2.212766 (-5950 1500);
PAINT ORANGE (-5950 1500);
DISPLAY INVISIBLE (-5950 1500);
FORCEPROP 2 LAST CDS_SEC 1
J 0
(-5650 1825);
PAINT MONO (-5650 1825);
DISPLAY INVISIBLE (-5650 1825);
FORCEPROP 2 LAST $SEC 1
J 0
(-5650 1825);
PAINT MONO (-5650 1825);
DISPLAY INVISIBLE (-5650 1825);
FORCEPROP 2 LAST ROOM DEBUG
J 0
(-5650 1825);
DISPLAY 1.617021 (-5650 1825);
PAINT WHITE (-5650 1825);
DISPLAY INVISIBLE (-5650 1825);
FORCEADD P3V3_STBY..1
(-5850 1100);
FORCEPROP 3 LASTPIN (-5850 1050) SIG_NAME P3V3_STBY\g
J 0
(-5840 1060);
DISPLAY 0.659574 (-5840 1060);
PAINT MONO (-5840 1060);
DISPLAY INVISIBLE (-5840 1060);
FORCEPROP 1 LAST HDL_POWER P3V3_STBY
J 0
(-6150 975);
DISPLAY 0.872340 (-6150 975);
PAINT ORANGE (-6150 975);
DISPLAY INVISIBLE (-6150 975);
FORCEPROP 1 LAST BODY_TYPE PLUMBING
J 0
(-5895 1057);
DISPLAY 0.340426 (-5895 1057);
PAINT GREEN (-5895 1057);
DISPLAY INVISIBLE (-5895 1057);
FORCEPROP 2 LAST CDS_LIB mstr_symbols
J 0
(-5850 1100);
PAINT ORANGE (-5850 1100);
DISPLAY INVISIBLE (-5850 1100);
FORCEPROP 1 LAST SIZE 1B
J 0
(-5805 1122);
DISPLAY 0.340426 (-5805 1122);
PAINT GREEN (-5805 1122);
DISPLAY INVISIBLE (-5805 1122);
FORCEPROP 1 LAST VOLTAGE +3.3V
J 0
(-5650 1250);
DISPLAY 1.021277 (-5650 1250);
PAINT SKYBLUE (-5650 1250);
DISPLAY INVISIBLE (-5650 1250);
FORCEPROP 1 LAST PATH I67
J 0
(-5805 1102);
DISPLAY 0.340426 (-5805 1102);
PAINT GREEN (-5805 1102);
DISPLAY INVISIBLE (-5805 1102);
FORCEADD TAP..1
R 2
(-5900 3475);
FORCEPROP 3 LASTPIN (-5850 3475) SIG_NAME P3E_CPU0_PE2_SS_C_TXN<14>
J 0
(-5840 3485);
DISPLAY 0.659574 (-5840 3485);
PAINT MONO (-5840 3485);
DISPLAY INVISIBLE (-5840 3485);
FORCEPROP 1 LASTPIN (-5850 3475) BN 14
J 2
(-5838 3483);
DISPLAY 0.680851 (-5838 3483);
PAINT GREEN (-5838 3483);
FORCEPROP 1 LAST HDL_TAP TRUE
J 2
(-6225 3350);
DISPLAY 0.872340 (-6225 3350);
PAINT ORANGE (-6225 3350);
DISPLAY INVISIBLE (-6225 3350);
FORCEPROP 1 LAST BODY_TYPE PLUMBING
J 2
(-5900 3525);
DISPLAY 0.872340 (-5900 3525);
PAINT GREEN (-5900 3525);
DISPLAY INVISIBLE (-5900 3525);
FORCEPROP 2 LAST CDS_LIB mstr_standard
J 0
(-5900 3475);
PAINT MONO (-5900 3475);
DISPLAY INVISIBLE (-5900 3475);
FORCEPROP 1 LAST PATH I7
J 2
(-5898 3475);
DISPLAY 0.872340 (-5898 3475);
PAINT GREEN (-5898 3475);
DISPLAY INVISIBLE (-5898 3475);
FORCEADD CAP_A..1
R 2
(-5450 825);
FORCEPROP 1 LAST PACK_TYPE 0402V
J 2
(-5500 625);
DISPLAY 0.617021 (-5500 625);
PAINT SKYBLUE (-5500 625);
FORCEPROP 1 LAST PART_NUMBER A36096-045
J 2
(-5500 675);
DISPLAY 0.617021 (-5500 675);
PAINT BLUE (-5500 675);
FORCEPROP 1 LAST TOLERANCE 10%
J 2
(-5500 775);
DISPLAY 0.617021 (-5500 775);
PAINT SKYBLUE (-5500 775);
FORCEPROP 1 LAST VALUE 0.01UF
J 2
(-5500 875);
DISPLAY 0.617021 (-5500 875);
PAINT SKYBLUE (-5500 875);
FORCEPROP 1 LASTPIN (-5450 725) $PN 2
J 2
(-5460 705);
DISPLAY 0.617021 (-5460 705);
PAINT WHITE (-5460 705);
FORCEPROP 1 LASTPIN (-5450 925) $PN 1
J 2
(-5460 905);
DISPLAY 0.617021 (-5460 905);
PAINT WHITE (-5460 905);
FORCEPROP 1 LAST MATERIAL X7R
J 2
(-5500 725);
DISPLAY 0.617021 (-5500 725);
PAINT SKYBLUE (-5500 725);
FORCEPROP 1 LAST VOLTAGE 25V
J 2
(-5500 825);
DISPLAY 0.617021 (-5500 825);
PAINT SKYBLUE (-5500 825);
FORCEPROP 1 LAST LOCATION C8W6
J 2
(-5500 925);
DISPLAY 0.617021 (-5500 925);
PAINT AQUA (-5500 925);
FORCEPROP 2 LAST ROOM DEBUG
J 2
(-5500 975);
DISPLAY 1.617021 (-5500 975);
PAINT WHITE (-5500 975);
DISPLAY INVISIBLE (-5500 975);
FORCEPROP 2 LAST SEC 1
J 2
(-5500 1025);
DISPLAY 1.510638 (-5500 1025);
PAINT MONO (-5500 1025);
DISPLAY INVISIBLE (-5500 1025);
FORCEPROP 2 LAST SEC_TYPE 0402V
J 0
(-5500 975);
DISPLAY 1.659574 (-5500 975);
PAINT ORANGE (-5500 975);
DISPLAY INVISIBLE (-5500 975);
FORCEPROP 2 LAST CDS_SEC 1
J 0
(-5500 975);
PAINT ORANGE (-5500 975);
DISPLAY INVISIBLE (-5500 975);
FORCEPROP 2 LAST CDS_LIB dev_discrete
J 0
(-5450 825);
PAINT ORANGE (-5450 825);
DISPLAY INVISIBLE (-5450 825);
FORCEPROP 2 LAST BOM_COST DEBUG
J 0
(-5500 975);
DISPLAY 1.617021 (-5500 975);
PAINT WHITE (-5500 975);
DISPLAY INVISIBLE (-5500 975);
FORCEPROP 1 LAST PATH I71
J 2
(-5500 975);
DISPLAY 0.978723 (-5500 975);
PAINT WHITE (-5500 975);
DISPLAY INVISIBLE (-5500 975);
FORCEADD GND..1
(-6375 1275);
FORCEPROP 3 LASTPIN (-6375 1325) SIG_NAME GND\g
J 0
(-6365 1335);
DISPLAY 0.659574 (-6365 1335);
PAINT MONO (-6365 1335);
DISPLAY INVISIBLE (-6365 1335);
FORCEPROP 1 LAST PATH I72
J 0
(-6300 1275);
DISPLAY 0.872340 (-6300 1275);
PAINT AQUA (-6300 1275);
DISPLAY INVISIBLE (-6300 1275);
FORCEPROP 1 LAST VOLTAGE 0.0V
J 0
(-6420 1232);
DISPLAY 0.340426 (-6420 1232);
PAINT SKYBLUE (-6420 1232);
DISPLAY INVISIBLE (-6420 1232);
FORCEPROP 2 LAST BOM_COST DEBUG
J 0
(-6850 1400);
DISPLAY 1.617021 (-6850 1400);
PAINT WHITE (-6850 1400);
DISPLAY INVISIBLE (-6850 1400);
FORCEPROP 2 LAST CDS_LIB mstr_symbols
J 0
(-6375 1275);
DISPLAY 2.212766 (-6375 1275);
PAINT ORANGE (-6375 1275);
DISPLAY INVISIBLE (-6375 1275);
FORCEPROP 1 LAST SIZE 1B
J 0
(-6300 1225);
DISPLAY 1.893617 (-6300 1225);
PAINT GREEN (-6300 1225);
DISPLAY INVISIBLE (-6300 1225);
FORCEPROP 2 LAST ROOM CPU_JTAG_DEBUG
J 0
(-6850 1350);
DISPLAY 1.617021 (-6850 1350);
PAINT WHITE (-6850 1350);
DISPLAY INVISIBLE (-6850 1350);
FORCEPROP 1 LAST BODY_TYPE PLUMBING
J 0
(-6420 1232);
DISPLAY 0.340426 (-6420 1232);
PAINT GREEN (-6420 1232);
DISPLAY INVISIBLE (-6420 1232);
FORCEPROP 1 LAST HDL_POWER GND
J 0
(-6375 1425);
PAINT GREEN (-6375 1425);
DISPLAY INVISIBLE (-6375 1425);
FORCEADD CAP_A..1
R 2
(-5850 825);
FORCEPROP 1 LASTPIN (-5850 725) $PN 2
J 2
(-5860 705);
DISPLAY 0.617021 (-5860 705);
PAINT WHITE (-5860 705);
FORCEPROP 1 LAST MATERIAL X6S
J 2
(-5900 725);
DISPLAY 0.617021 (-5900 725);
PAINT SKYBLUE (-5900 725);
FORCEPROP 1 LAST VOLTAGE 6.3V
J 2
(-5900 825);
DISPLAY 0.617021 (-5900 825);
PAINT SKYBLUE (-5900 825);
FORCEPROP 1 LAST PACK_TYPE 0402V
J 2
(-5900 625);
DISPLAY 0.617021 (-5900 625);
PAINT SKYBLUE (-5900 625);
FORCEPROP 1 LAST TOLERANCE 10%
J 2
(-5900 775);
DISPLAY 0.617021 (-5900 775);
PAINT SKYBLUE (-5900 775);
FORCEPROP 1 LAST VALUE 1.0UF
J 2
(-5900 875);
DISPLAY 0.617021 (-5900 875);
PAINT SKYBLUE (-5900 875);
FORCEPROP 1 LAST PART_NUMBER D97712-004
J 2
(-5900 675);
DISPLAY 0.617021 (-5900 675);
PAINT BLUE (-5900 675);
FORCEPROP 1 LAST LOCATION C8W5
J 2
(-5900 925);
DISPLAY 0.617021 (-5900 925);
PAINT AQUA (-5900 925);
FORCEPROP 1 LASTPIN (-5850 925) $PN 1
J 2
(-5860 905);
DISPLAY 0.617021 (-5860 905);
PAINT WHITE (-5860 905);
FORCEPROP 2 LAST ROOM DEBUG
J 2
(-5900 975);
DISPLAY 1.617021 (-5900 975);
PAINT WHITE (-5900 975);
DISPLAY INVISIBLE (-5900 975);
FORCEPROP 2 LAST $SEC 1
J 0
(-5900 1025);
PAINT MONO (-5900 1025);
DISPLAY INVISIBLE (-5900 1025);
FORCEPROP 2 LAST CDS_SEC 1
J 0
(-5900 1025);
PAINT MONO (-5900 1025);
DISPLAY INVISIBLE (-5900 1025);
FORCEPROP 2 LAST CDS_LIB dev_discrete
J 0
(-5850 825);
PAINT ORANGE (-5850 825);
DISPLAY INVISIBLE (-5850 825);
FORCEPROP 2 LAST BOM_COST DEBUG
J 0
(-5900 975);
DISPLAY 1.617021 (-5900 975);
PAINT WHITE (-5900 975);
DISPLAY INVISIBLE (-5900 975);
FORCEPROP 1 LAST PATH I74
J 2
(-5900 975);
DISPLAY 0.978723 (-5900 975);
PAINT WHITE (-5900 975);
DISPLAY INVISIBLE (-5900 975);
FORCEADD GND..1
(-5850 475);
FORCEPROP 3 LASTPIN (-5850 525) SIG_NAME GND\g
J 0
(-5840 535);
DISPLAY 0.659574 (-5840 535);
PAINT MONO (-5840 535);
DISPLAY INVISIBLE (-5840 535);
FORCEPROP 1 LAST HDL_POWER GND
J 0
(-5850 625);
PAINT GREEN (-5850 625);
DISPLAY INVISIBLE (-5850 625);
FORCEPROP 1 LAST BODY_TYPE PLUMBING
J 0
(-5895 432);
DISPLAY 0.340426 (-5895 432);
PAINT GREEN (-5895 432);
DISPLAY INVISIBLE (-5895 432);
FORCEPROP 2 LAST ROOM CPU_JTAG_DEBUG
J 0
(-6325 550);
DISPLAY 1.617021 (-6325 550);
PAINT WHITE (-6325 550);
DISPLAY INVISIBLE (-6325 550);
FORCEPROP 1 LAST SIZE 1B
J 0
(-5775 425);
DISPLAY 1.893617 (-5775 425);
PAINT GREEN (-5775 425);
DISPLAY INVISIBLE (-5775 425);
FORCEPROP 2 LAST CDS_LIB mstr_symbols
J 0
(-5850 475);
DISPLAY 2.212766 (-5850 475);
PAINT ORANGE (-5850 475);
DISPLAY INVISIBLE (-5850 475);
FORCEPROP 2 LAST BOM_COST DEBUG
J 0
(-6325 600);
DISPLAY 1.617021 (-6325 600);
PAINT WHITE (-6325 600);
DISPLAY INVISIBLE (-6325 600);
FORCEPROP 1 LAST VOLTAGE 0.0V
J 0
(-5895 432);
DISPLAY 0.340426 (-5895 432);
PAINT SKYBLUE (-5895 432);
DISPLAY INVISIBLE (-5895 432);
FORCEPROP 1 LAST PATH I75
J 0
(-5775 475);
DISPLAY 0.872340 (-5775 475);
PAINT AQUA (-5775 475);
DISPLAY INVISIBLE (-5775 475);
FORCEADD OFFPAGE..1
(-6100 1950);
FORCEPROP 2 LAST $XR0 145 
J 0
(-6352 1950);
DISPLAY 0.638298 (-6352 1950);
PAINT MONO (-6352 1950);
FORCEPROP 2 LAST CDS_LIB mstr_standard
J 0
(-6100 1950);
PAINT ORANGE (-6100 1950);
DISPLAY INVISIBLE (-6100 1950);
FORCEPROP 1 LAST OFFPAGE TRUE
J 0
(-5775 1825);
DISPLAY 0.872340 (-5775 1825);
PAINT GREEN (-5775 1825);
DISPLAY INVISIBLE (-5775 1825);
FORCEPROP 1 LAST COMMENT_BODY TRUE
J 0
(-5975 1850);
DISPLAY 0.872340 (-5975 1850);
PAINT GREEN (-5975 1850);
DISPLAY INVISIBLE (-5975 1850);
FORCEPROP 2 LAST PATH I77
J 0
(-6550 2000);
DISPLAY 1.021277 (-6550 2000);
PAINT ORANGE (-6550 2000);
DISPLAY INVISIBLE (-6550 2000);
FORCEADD RES..2
(-5500 2150);
FORCEPROP 1 LASTPIN (-5500 2250) $PN 1
J 0
(-5495 2212);
DISPLAY 0.617021 (-5495 2212);
PAINT ORANGE (-5495 2212);
FORCEPROP 1 LAST TOLERANCE 1%
J 0
(-5455 2175);
DISPLAY 0.617021 (-5455 2175);
PAINT SKYBLUE (-5455 2175);
FORCEPROP 1 LAST WATTAGE 1/16W
J 0
(-5460 2125);
DISPLAY 0.617021 (-5460 2125);
PAINT SKYBLUE (-5460 2125);
FORCEPROP 1 LAST PART_NUMBER G21796-072
J 0
(-5460 2025);
DISPLAY 0.617021 (-5460 2025);
PAINT BLUE (-5460 2025);
FORCEPROP 1 LAST LOCATION R8W15
J 0
(-5455 2275);
DISPLAY 0.617021 (-5455 2275);
PAINT AQUA (-5455 2275);
FORCEPROP 1 LASTPIN (-5500 2050) $PN 2
J 0
(-5495 2060);
DISPLAY 0.617021 (-5495 2060);
PAINT ORANGE (-5495 2060);
FORCEPROP 1 LAST PACK_TYPE 0402
J 0
(-5460 1975);
DISPLAY 0.617021 (-5460 1975);
PAINT SKYBLUE (-5460 1975);
FORCEPROP 1 LAST VALUE 4.75K
J 0
(-5455 2225);
DISPLAY 0.617021 (-5455 2225);
PAINT SKYBLUE (-5455 2225);
FORCEPROP 1 LAST MATERIAL CHIP
J 0
(-5460 2075);
DISPLAY 0.617021 (-5460 2075);
PAINT SKYBLUE (-5460 2075);
FORCEPROP 2 LAST SEC 1
J 0
(-5450 2375);
DISPLAY 0.680851 (-5450 2375);
PAINT MONO (-5450 2375);
DISPLAY INVISIBLE (-5450 2375);
FORCEPROP 2 LAST SEC_TYPE 0402
J 0
(-5450 2375);
DISPLAY 1.021277 (-5450 2375);
PAINT ORANGE (-5450 2375);
DISPLAY INVISIBLE (-5450 2375);
FORCEPROP 2 LAST BOM_COST SM_CONTROLLER
J 0
(-5550 2300);
DISPLAY 1.021277 (-5550 2300);
PAINT ORANGE (-5550 2300);
DISPLAY INVISIBLE (-5550 2300);
FORCEPROP 2 LAST CDS_LIB mstr_discrete
J 0
(-5500 2150);
PAINT MONO (-5500 2150);
DISPLAY INVISIBLE (-5500 2150);
FORCEPROP 2 LAST ROOM BMC_MISC
J 0
(-5550 2250);
DISPLAY 1.021277 (-5550 2250);
PAINT ORANGE (-5550 2250);
DISPLAY INVISIBLE (-5550 2250);
FORCEPROP 1 LAST PATH I78
J 0
(-5450 2325);
DISPLAY 0.978723 (-5450 2325);
PAINT WHITE (-5450 2325);
DISPLAY INVISIBLE (-5450 2325);
FORCEPROP 2 LAST CDS_LOCATION R8W15
J 0
(-5455 2275);
DISPLAY 0.617021 (-5455 2275);
PAINT AQUA (-5455 2275);
DISPLAY INVISIBLE (-5455 2275);
FORCEADD P3V3_STBY..1
(-5500 2350);
FORCEPROP 3 LASTPIN (-5500 2300) SIG_NAME P3V3_STBY\g
J 0
(-5490 2310);
DISPLAY 0.659574 (-5490 2310);
PAINT MONO (-5490 2310);
DISPLAY INVISIBLE (-5490 2310);
FORCEPROP 1 LAST PATH I79
J 0
(-5455 2352);
DISPLAY 0.340426 (-5455 2352);
PAINT GREEN (-5455 2352);
DISPLAY INVISIBLE (-5455 2352);
FORCEPROP 1 LAST VOLTAGE 3.3V
J 0
(-5545 2307);
DISPLAY 0.340426 (-5545 2307);
PAINT SKYBLUE (-5545 2307);
DISPLAY INVISIBLE (-5545 2307);
FORCEPROP 2 LAST CDS_LIB mstr_symbols
J 0
(-5500 2350);
PAINT MONO (-5500 2350);
DISPLAY INVISIBLE (-5500 2350);
FORCEPROP 1 LAST SIZE 1B
J 0
(-5455 2372);
DISPLAY 0.340426 (-5455 2372);
PAINT GREEN (-5455 2372);
DISPLAY INVISIBLE (-5455 2372);
FORCEPROP 1 LAST BODY_TYPE PLUMBING
J 0
(-5545 2307);
DISPLAY 0.340426 (-5545 2307);
PAINT GREEN (-5545 2307);
DISPLAY INVISIBLE (-5545 2307);
FORCEPROP 1 LAST HDL_POWER P3V3_STBY
J 0
(-5800 2225);
DISPLAY 0.872340 (-5800 2225);
PAINT ORANGE (-5800 2225);
DISPLAY INVISIBLE (-5800 2225);
FORCEADD TAP..1
R 2
(-5900 3825);
FORCEPROP 3 LASTPIN (-5850 3825) SIG_NAME P3E_CPU0_PE2_SS_C_TXN<12>
J 0
(-5840 3835);
DISPLAY 0.659574 (-5840 3835);
PAINT MONO (-5840 3835);
DISPLAY INVISIBLE (-5840 3835);
FORCEPROP 1 LASTPIN (-5850 3825) BN 12
J 2
(-5838 3833);
DISPLAY 0.680851 (-5838 3833);
PAINT GREEN (-5838 3833);
FORCEPROP 1 LAST HDL_TAP TRUE
J 2
(-6225 3700);
DISPLAY 0.872340 (-6225 3700);
PAINT ORANGE (-6225 3700);
DISPLAY INVISIBLE (-6225 3700);
FORCEPROP 1 LAST BODY_TYPE PLUMBING
J 2
(-5900 3875);
DISPLAY 0.872340 (-5900 3875);
PAINT GREEN (-5900 3875);
DISPLAY INVISIBLE (-5900 3875);
FORCEPROP 2 LAST CDS_LIB mstr_standard
J 0
(-5900 3825);
PAINT MONO (-5900 3825);
DISPLAY INVISIBLE (-5900 3825);
FORCEPROP 1 LAST PATH I8
J 2
(-5898 3825);
DISPLAY 0.872340 (-5898 3825);
PAINT GREEN (-5898 3825);
DISPLAY INVISIBLE (-5898 3825);
FORCEADD OFFPAGE..5
(-7150 1500);
FORCEPROP 2 LAST $XR0 189 
J 0
(-7405 1500);
DISPLAY 0.638298 (-7405 1500);
PAINT MONO (-7405 1500);
FORCEPROP 1 LAST COMMENT_BODY TRUE
J 0
(-7050 1425);
DISPLAY 0.872340 (-7050 1425);
PAINT GREEN (-7050 1425);
DISPLAY INVISIBLE (-7050 1425);
FORCEPROP 1 LAST OFFPAGE TRUE
J 0
(-6825 1375);
DISPLAY 0.872340 (-6825 1375);
PAINT GREEN (-6825 1375);
DISPLAY INVISIBLE (-6825 1375);
FORCEPROP 2 LAST CDS_LIB mstr_standard
J 0
(-7150 1500);
PAINT ORANGE (-7150 1500);
DISPLAY INVISIBLE (-7150 1500);
FORCEPROP 2 LAST PATH I80
J 0
(-7400 1550);
DISPLAY 1.021277 (-7400 1550);
PAINT ORANGE (-7400 1550);
DISPLAY INVISIBLE (-7400 1550);
FORCEADD OFFPAGE..1
(-4700 2000);
FORCEPROP 2 LAST $XR0 191 
J 0
(-4952 2000);
DISPLAY 0.638298 (-4952 2000);
PAINT MONO (-4952 2000);
FORCEPROP 2 LAST CDS_LIB mstr_standard
J 0
(-4700 2000);
PAINT ORANGE (-4700 2000);
DISPLAY INVISIBLE (-4700 2000);
FORCEPROP 1 LAST OFFPAGE TRUE
J 0
(-4375 1875);
DISPLAY 0.872340 (-4375 1875);
PAINT GREEN (-4375 1875);
DISPLAY INVISIBLE (-4375 1875);
FORCEPROP 1 LAST COMMENT_BODY TRUE
J 0
(-4575 1900);
DISPLAY 0.872340 (-4575 1900);
PAINT GREEN (-4575 1900);
DISPLAY INVISIBLE (-4575 1900);
FORCEPROP 2 LAST PATH I81
J 0
(-4950 2050);
DISPLAY 1.021277 (-4950 2050);
PAINT ORANGE (-4950 2050);
DISPLAY INVISIBLE (-4950 2050);
FORCEADD OFFPAGE..4
(-1050 3175);
FORCEPROP 2 LAST $XR0 189 
J 0
(-864 3175);
DISPLAY 0.638298 (-864 3175);
PAINT MONO (-864 3175);
FORCEPROP 1 LAST COMMENT_BODY TRUE
J 0
(-1075 3075);
DISPLAY 0.872340 (-1075 3075);
PAINT GREEN (-1075 3075);
DISPLAY INVISIBLE (-1075 3075);
FORCEPROP 1 LAST OFFPAGE TRUE
J 0
(-725 3050);
DISPLAY 0.872340 (-725 3050);
PAINT GREEN (-725 3050);
DISPLAY INVISIBLE (-725 3050);
FORCEPROP 2 LAST CDS_LIB mstr_standard
J 0
(-1050 3175);
PAINT MONO (-1050 3175);
DISPLAY INVISIBLE (-1050 3175);
FORCEPROP 2 LAST PATH I82
J 0
(-600 3225);
DISPLAY 1.021277 (-600 3225);
PAINT ORANGE (-600 3225);
DISPLAY INVISIBLE (-600 3225);
FORCEADD OFFPAGE..4
(-1050 3125);
FORCEPROP 2 LAST $XR0 189 
J 0
(-864 3125);
DISPLAY 0.638298 (-864 3125);
PAINT MONO (-864 3125);
FORCEPROP 2 LAST PATH I83
J 0
(-600 3175);
DISPLAY 1.021277 (-600 3175);
PAINT ORANGE (-600 3175);
DISPLAY INVISIBLE (-600 3175);
FORCEPROP 2 LAST CDS_LIB mstr_standard
J 0
(-1050 3125);
PAINT MONO (-1050 3125);
DISPLAY INVISIBLE (-1050 3125);
FORCEPROP 1 LAST OFFPAGE TRUE
J 0
(-725 3000);
DISPLAY 0.872340 (-725 3000);
PAINT GREEN (-725 3000);
DISPLAY INVISIBLE (-725 3000);
FORCEPROP 1 LAST COMMENT_BODY TRUE
J 0
(-1075 3025);
DISPLAY 0.872340 (-1075 3025);
PAINT GREEN (-1075 3025);
DISPLAY INVISIBLE (-1075 3025);
FORCEADD TAP..1
R 2
(-5900 3675);
FORCEPROP 3 LASTPIN (-5850 3675) SIG_NAME P3E_CPU0_PE2_SS_C_TXN<13>
J 0
(-5840 3685);
DISPLAY 0.659574 (-5840 3685);
PAINT MONO (-5840 3685);
DISPLAY INVISIBLE (-5840 3685);
FORCEPROP 1 LASTPIN (-5850 3675) BN 13
J 2
(-5838 3683);
DISPLAY 0.680851 (-5838 3683);
PAINT GREEN (-5838 3683);
FORCEPROP 1 LAST HDL_TAP TRUE
J 2
(-6225 3550);
DISPLAY 0.872340 (-6225 3550);
PAINT ORANGE (-6225 3550);
DISPLAY INVISIBLE (-6225 3550);
FORCEPROP 1 LAST BODY_TYPE PLUMBING
J 2
(-5900 3725);
DISPLAY 0.872340 (-5900 3725);
PAINT GREEN (-5900 3725);
DISPLAY INVISIBLE (-5900 3725);
FORCEPROP 2 LAST CDS_LIB mstr_standard
J 0
(-5900 3675);
PAINT MONO (-5900 3675);
DISPLAY INVISIBLE (-5900 3675);
FORCEPROP 1 LAST PATH I9
J 2
(-5898 3675);
DISPLAY 0.872340 (-5898 3675);
PAINT GREEN (-5898 3675);
DISPLAY INVISIBLE (-5898 3675);
FORCEADD INTEL_CORP_BPAGE..1
(0 0);
FORCEPROP 1 LAST CDS_CON_LAST_MODIFIED Fri Jun 16 17:49:29 2017
J 0
(-1425 325);
PAINT ORANGE (-1425 325);
DISPLAY INVISIBLE (-1425 325);
FORCEPROP 1 LAST CUSTOM_TXT_CDS <CURRENT_DESIGN_SHEET> OF <TOTAL_DESIGN_SHEETS>
J 0
(-500 25);
PAINT ORANGE (-500 25);
FORCEPROP 1 LAST CUSTOM_TXT_CDS <CON_LAST_MODIFIED>
J 0
(-4000 100);
PAINT ORANGE (-4000 100);
FORCEPROP 2 LAST CUSTOM_TXT_CDS <XR_PAGE_TITLE>
J 0
(-7890 5250);
DISPLAY 0.638298 (-7890 5250);
PAINT PINK (-7890 5250);
DISPLAY INVISIBLE (-7890 5250);
FORCEPROP 1 LAST SCH_TITLE X8 SLOT FOR PCIE RISER CARD
J 0
(-7950 50);
DISPLAY 2.468085 (-7950 50);
PAINT ORANGE (-7950 50);
FORCEPROP 1 LAST COMMENT_BODY TRUE
J 0
(12 12);
DISPLAY 0.468085 (12 12);
PAINT GREEN (12 12);
DISPLAY INVISIBLE (12 12);
FORCEPROP 2 LAST PAGE_BORDER TRUE
J 0
(-7890 5250);
DISPLAY 0.638298 (-7890 5250);
PAINT PINK (-7890 5250);
DISPLAY INVISIBLE (-7890 5250);
FORCEPROP 2 LAST CDS_LIB mstr_symbols
J 0
(0 0);
PAINT MONO (0 0);
DISPLAY INVISIBLE (0 0);
FORCEPROP 2 LAST CDS_XR_PAGE_TITLE CR-245 : @BASEBOARD_FAB2_LIB.BASEBOARD_FAB2(SCH_1):PAGE245
J 0
(-7890 5250);
DISPLAY 0.638298 (-7890 5250);
PAINT PINK (-7890 5250);
DISPLAY INVISIBLE (-7890 5250);
WIRE 16 -1 (-4725 2875)(-4725 3125);
WIRE 16 -1 (-4725 3125)(-4725 3275);
WIRE 16 -1 (-4250 3125)(-4725 3125);
WIRE 16 -1 (-4725 3275)(-4725 3425);
WIRE 16 -1 (-4725 3275)(-4250 3275);
WIRE 16 -1 (-4725 3425)(-4725 3575);
WIRE 16 -1 (-4725 3425)(-4250 3425);
WIRE 16 -1 (-4725 3575)(-4725 3725);
WIRE 16 -1 (-4725 3575)(-4250 3575);
WIRE 16 -1 (-4725 3725)(-4725 3875);
WIRE 16 -1 (-4725 3725)(-4250 3725);
WIRE 16 -1 (-4725 3875)(-4725 4025);
WIRE 16 -1 (-4725 3875)(-4250 3875);
WIRE 16 -1 (-4725 4025)(-4725 4175);
WIRE 16 -1 (-4725 4025)(-4250 4025);
WIRE 16 -1 (-4725 4175)(-4725 4325);
WIRE 16 -1 (-4725 4175)(-4250 4175);
WIRE 16 -1 (-4725 4525)(-4725 4325);
WIRE 16 -1 (-4250 4325)(-4725 4325);
WIRE 16 -1 (-4725 4525)(-4250 4525);
WIRE 16 -1 (-4275 2925)(-4275 2675);
WIRE 16 -1 (-4250 2925)(-4275 2925);
WIRE 16 -1 (-4250 4625)(-4425 4625);
WIRE 16 -1 (-3375 3075)(-3375 2675);
WIRE 16 -1 (-3375 3225)(-3375 3075);
WIRE 16 -1 (-3750 3075)(-3375 3075);
FORCEPROP 0 LAST VOLTAGE 0
J 0
(-3812 3075);
PAINT MONO (-3812 3075);
DISPLAY INVISIBLE (-3812 3075);
FORCEPROP 0 LAST CDS_PHYS_NET_NAME GND
J 0
(-3812 3122);
PAINT MONO (-3812 3122);
DISPLAY INVISIBLE (-3812 3122);
FORCEPROP 0 LAST ROOM TBD
J 0
(-3812 3169);
PAINT MONO (-3812 3169);
DISPLAY INVISIBLE (-3812 3169);
FORCEPROP 0 LAST BOM_COST TBD
J 0
(-3812 3216);
PAINT MONO (-3812 3216);
DISPLAY INVISIBLE (-3812 3216);
WIRE 16 -1 (-3375 3375)(-3375 3225);
WIRE 16 -1 (-3750 3225)(-3375 3225);
WIRE 16 -1 (-3375 3525)(-3375 3375);
WIRE 16 -1 (-3750 3375)(-3375 3375);
WIRE 16 -1 (-3375 3675)(-3375 3525);
WIRE 16 -1 (-3750 3525)(-3375 3525);
WIRE 16 -1 (-3375 3825)(-3375 3675);
WIRE 16 -1 (-3750 3675)(-3375 3675);
WIRE 16 -1 (-3375 3975)(-3375 3825);
WIRE 16 -1 (-3750 3825)(-3375 3825);
WIRE 16 -1 (-3375 4125)(-3375 3975);
WIRE 16 -1 (-3750 3975)(-3375 3975);
WIRE 16 -1 (-3375 4275)(-3375 4125);
WIRE 16 -1 (-3750 4125)(-3375 4125);
WIRE 16 -1 (-3375 4425)(-3375 4275);
WIRE 16 -1 (-3750 4275)(-3375 4275);
WIRE 16 -1 (-3750 4425)(-3375 4425);
WIRE 16 -1 (-5850 1050)(-5850 1000);
WIRE 16 -1 (-5850 1000)(-5450 1000);
WIRE 16 -1 (-5850 925)(-5850 1000);
WIRE 16 -1 (-5450 1350)(-5450 1000);
WIRE 16 -1 (-5450 925)(-5450 1000);
WIRE 16 -1 (-5600 1350)(-5450 1350);
WIRE 16 -1 (-6375 1350)(-6375 1325);
WIRE 16 -1 (-6300 1350)(-6375 1350);
WIRE 16 -1 (-5850 525)(-5850 550);
WIRE 16 -1 (-5850 550)(-5450 550);
WIRE 16 -1 (-5850 725)(-5850 550);
WIRE 16 -1 (-5450 550)(-5450 725);
WIRE 16 -1 (-5500 2250)(-5500 2300);
WIRE 17 -1 (-5325 3550)(-5325 3350);
WIRE 17 -1 (-5325 3650)(-5325 3550);
WIRE 17 -1 (-5325 3800)(-5325 3650);
WIRE 17 -1 (-5325 4000)(-5325 3800);
WIRE 17 -1 (-5325 4100)(-5325 4000);
WIRE 17 -1 (-5325 4250)(-5325 4100);
WIRE 17 -1 (-5325 4400)(-5325 4250);
WIRE 17 -1 (-5325 4550)(-6850 4550);
FORCEPROP 2 LAST SIG_NAME P3E_CPU0_PE2_SS_C_TXP<15:8>
J 0
(-6810 4560);
DISPLAY 0.617021 (-6810 4560);
PAINT ORANGE (-6810 4560);
WIRE 17 -1 (-5325 4550)(-5325 4400);
WIRE 17 -1 (-5950 3500)(-5950 3400);
WIRE 17 -1 (-5950 3700)(-5950 3500);
WIRE 17 -1 (-5950 3850)(-5950 3700);
WIRE 17 -1 (-5950 3950)(-5950 3850);
WIRE 17 -1 (-5950 3950)(-5950 4150);
WIRE 17 -1 (-5950 4775)(-6850 4775);
FORCEPROP 2 LAST SIG_NAME P3E_CPU0_PE2_SS_C_TXN<15:8>
J 0
(-6810 4785);
DISPLAY 0.617021 (-6810 4785);
PAINT ORANGE (-6810 4785);
WIRE 17 -1 (-5950 4450)(-5950 4775);
WIRE 17 -1 (-5950 4150)(-5950 4300);
WIRE 17 -1 (-5950 4300)(-5950 4450);
WIRE 17 -1 (-2225 3300)(-2225 3450);
WIRE 17 -1 (-2225 3450)(-2225 3650);
WIRE 17 -1 (-2225 4475)(-1300 4475);
FORCEPROP 2 LAST SIG_NAME P3E_CPU0_PE2_SS_RXP<15:8>
J 0
(-2185 4485);
DISPLAY 0.617021 (-2185 4485);
PAINT ORANGE (-2185 4485);
WIRE 17 -1 (-2225 3650)(-2225 3750);
WIRE 17 -1 (-2225 3750)(-2225 3900);
WIRE 17 -1 (-2225 4475)(-2225 4350);
WIRE 17 -1 (-2225 4350)(-2225 4200);
WIRE 17 -1 (-2225 4050)(-2225 3900);
WIRE 17 -1 (-2225 4050)(-2225 4200);
WIRE 17 -1 (-2425 3350)(-2425 3500);
WIRE 17 -1 (-2425 3500)(-2425 3600);
WIRE 17 -1 (-2425 4600)(-1300 4600);
FORCEPROP 2 LAST SIG_NAME P3E_CPU0_PE2_SS_RXN<15:8>
J 0
(-2160 4610);
DISPLAY 0.617021 (-2160 4610);
PAINT ORANGE (-2160 4610);
WIRE 17 -1 (-2425 3600)(-2425 3800);
WIRE 17 -1 (-2425 3800)(-2425 3950);
WIRE 17 -1 (-2425 4600)(-2425 4400);
WIRE 17 -1 (-2425 4250)(-2425 4400);
WIRE 17 -1 (-2425 3950)(-2425 4100);
WIRE 17 -1 (-2425 4100)(-2425 4250);
WIRE 16 -1 (-5850 3925)(-4250 3925);
WIRE 3 2175 (-7900 4900)(-100 4900);
WIRE 3 2175 (-100 4900)(-100 2550);
WIRE 3 2175 (-7900 4900)(-7900 2550);
WIRE 3 2175 (-7900 2550)(-100 2550);
WIRE 3 682 (-2825 2975)(-2575 2975);
WIRE 3 682 (-2825 3225)(-2825 2975);
WIRE 3 682 (-2575 2975)(-2575 3225);
WIRE 3 682 (-2575 3225)(-2825 3225);
WIRE 16 -1 (-3750 3025)(-2800 3025);
FORCEPROP 2 LAST SIG_NAME JTAG_RISER_TRST
J 0
(-3285 3035);
DISPLAY 0.638298 (-3285 3035);
PAINT ORANGE (-3285 3035);
FORCEPROP 2 LASTPROP $XRERR UNIQUE?
J 0
(-3525 3035);
DISPLAY 0.638298 (-3525 3035);
PAINT MONO (-3525 3035);
DISPLAY INVISIBLE (-3525 3035);
WIRE 16 -1 (-1100 3125)(-2600 3125);
FORCEPROP 2 LAST SIG_NAME JTAG_PLD_TCK_MUX
J 0
(-1535 3135);
DISPLAY 0.617021 (-1535 3135);
PAINT ORANGE (-1535 3135);
WIRE 16 -1 (-2600 3025)(-1100 3025);
FORCEPROP 2 LAST SIG_NAME JTAG_BMC_TRST_N
J 0
(-1535 3035);
DISPLAY 0.638298 (-1535 3035);
PAINT ORANGE (-1535 3035);
WIRE 16 -1 (-4250 3225)(-6400 3225);
FORCEPROP 2 LAST SIG_NAME JTAG_RISER_TDI
J 0
(-5285 3235);
DISPLAY 0.638298 (-5285 3235);
PAINT ORANGE (-5285 3235);
FORCEPROP 2 LASTPROP $XRERR UNIQUE?
J 0
(-5525 3235);
DISPLAY 0.638298 (-5525 3235);
PAINT MONO (-5525 3235);
DISPLAY INVISIBLE (-5525 3235);
WIRE 16 -1 (-5225 3325)(-4250 3325);
WIRE 16 -1 (-5850 3375)(-4250 3375);
WIRE 16 -1 (-4250 3175)(-6400 3175);
FORCEPROP 2 LAST SIG_NAME JTAG_RISER_TDO
J 0
(-5285 3185);
DISPLAY 0.638298 (-5285 3185);
PAINT ORANGE (-5285 3185);
FORCEPROP 2 LASTPROP $XRERR UNIQUE?
J 0
(-5525 3185);
DISPLAY 0.638298 (-5525 3185);
PAINT MONO (-5525 3185);
DISPLAY INVISIBLE (-5525 3185);
WIRE 3 2175 (-5825 3125)(-4975 3125);
WIRE 3 2175 (-4975 3125)(-4975 2950);
WIRE 3 2175 (-5825 3125)(-5825 2950);
WIRE 3 2175 (-5825 2950)(-4975 2950);
WIRE 16 -1 (-5425 3075)(-4250 3075);
FORCEPROP 0 LAST SIG_NAME USB2_P02_DN
J 1
(-5200 3085);
DISPLAY 0.617021 (-5200 3085);
PAINT ORANGE (-5200 3085);
WIRE 16 -1 (-5850 3475)(-4250 3475);
WIRE 16 -1 (-3750 3925)(-2525 3925);
WIRE 16 -1 (-3750 3875)(-2325 3875);
WIRE 16 -1 (-3750 3775)(-2525 3775);
WIRE 16 -1 (-3750 3725)(-2325 3725);
WIRE 16 -1 (-3750 3625)(-2325 3625);
WIRE 16 -1 (-3750 3475)(-2525 3475);
WIRE 16 -1 (-3750 3425)(-2325 3425);
WIRE 16 -1 (-3750 3325)(-2525 3325);
WIRE 16 -1 (-3750 3275)(-2325 3275);
WIRE 16 -1 (-3750 3175)(-2800 3175);
FORCEPROP 2 LAST SIG_NAME JTAG_RISER_TMS
J 0
(-3285 3185);
DISPLAY 0.638298 (-3285 3185);
PAINT ORANGE (-3285 3185);
FORCEPROP 2 LASTPROP $XRERR UNIQUE?
J 0
(-3525 3185);
DISPLAY 0.638298 (-3525 3185);
PAINT MONO (-3525 3185);
DISPLAY INVISIBLE (-3525 3185);
WIRE 16 -1 (-3750 3575)(-2525 3575);
WIRE 16 -1 (-5850 3825)(-4250 3825);
WIRE 3 682 (-6375 3275)(-6625 3275);
WIRE 3 682 (-6375 3125)(-6375 3275);
WIRE 3 682 (-6625 3275)(-6625 3125);
WIRE 3 682 (-6625 3125)(-6375 3125);
WIRE 16 -1 (-6600 3175)(-7200 3175);
FORCEPROP 2 LAST SIG_NAME JTAG_RISER_TDO_R
J 0
(-7135 3185);
DISPLAY 0.638298 (-7135 3185);
PAINT ORANGE (-7135 3185);
FORCEPROP 2 LASTPROP $XR0 245 
J 0
(-7296 3175);
DISPLAY 0.638298 (-7296 3175);
PAINT MONO (-7296 3175);
WIRE 16 -1 (-6600 3225)(-7200 3225);
FORCEPROP 2 LAST SIG_NAME JTAG_RISER_TDI_R
J 0
(-7135 3235);
DISPLAY 0.638298 (-7135 3235);
PAINT ORANGE (-7135 3235);
FORCEPROP 2 LASTPROP $XR0 245 
J 0
(-7296 3225);
DISPLAY 0.638298 (-7296 3225);
PAINT MONO (-7296 3225);
WIRE 16 -1 (-5425 3025)(-4250 3025);
FORCEPROP 0 LAST SIG_NAME USB2_P02_DP
J 1
(-5200 3035);
DISPLAY 0.617021 (-5200 3035);
PAINT ORANGE (-5200 3035);
WIRE 3 682 (-2900 2500)(-7600 2500);
WIRE 3 682 (-2900 450)(-2900 2500);
WIRE 3 682 (-7600 2500)(-7600 450);
WIRE 3 682 (-7600 450)(-2900 450);
WIRE 16 -1 (-5500 1650)(-5600 1650);
WIRE 16 -1 (-5500 1950)(-6050 1950);
FORCEPROP 2 LAST SIG_NAME JTAG_RISER_N
J 0
(-5985 1960);
DISPLAY 0.638298 (-5985 1960);
PAINT ORANGE (-5985 1960);
WIRE 16 -1 (-5500 1950)(-5500 1650);
WIRE 16 -1 (-5500 2050)(-5500 1950);
WIRE 16 -1 (-4150 1950)(-5500 1950);
WIRE 16 -1 (-5600 1450)(-4250 1450);
WIRE 16 -1 (-4250 2000)(-4650 2000);
FORCEPROP 2 LAST SIG_NAME JTAG_PLD_TDO
J 0
(-4635 2010);
DISPLAY 0.617021 (-4635 2010);
PAINT ORANGE (-4635 2010);
WIRE 16 -1 (-4250 2000)(-4250 1450);
WIRE 16 -1 (-4150 2000)(-4250 2000);
WIRE 16 -1 (-2600 3175)(-1100 3175);
FORCEPROP 2 LAST SIG_NAME JTAG_PLD_TMS_MUX
J 0
(-1535 3185);
DISPLAY 0.617021 (-1535 3185);
PAINT ORANGE (-1535 3185);
WIRE 16 -1 (-3100 2000)(-3650 2000);
FORCEPROP 2 LAST SIG_NAME JTAG_RISER_TDI_R
J 0
(-3585 2010);
DISPLAY 0.638298 (-3585 2010);
PAINT ORANGE (-3585 2010);
FORCEPROP 2 LASTPROP $XR0 245 
J 0
(-3070 2000);
DISPLAY 0.638298 (-3070 2000);
PAINT MONO (-3070 2000);
WIRE 16 -1 (-5225 3525)(-4250 3525);
WIRE 16 -1 (-5225 3775)(-4250 3775);
WIRE 16 -1 (-5850 3675)(-4250 3675);
WIRE 16 -1 (-3750 3125)(-2800 3125);
FORCEPROP 2 LAST SIG_NAME JTAG_RISER_TCK
J 0
(-3285 3135);
DISPLAY 0.638298 (-3285 3135);
PAINT ORANGE (-3285 3135);
FORCEPROP 2 LASTPROP $XRERR UNIQUE?
J 0
(-3525 3135);
DISPLAY 0.638298 (-3525 3135);
PAINT MONO (-3525 3135);
DISPLAY INVISIBLE (-3525 3135);
WIRE 16 -1 (-5225 3625)(-4250 3625);
WIRE 3 2175 (-4025 2950)(-3725 2950);
WIRE 3 2175 (-3725 3000)(-3725 2950);
WIRE 3 2175 (-4025 3000)(-4025 2950);
WIRE 3 2175 (-4025 3000)(-3725 3000);
WIRE 16 -1 (-3750 4075)(-2525 4075);
WIRE 16 -1 (-3750 4175)(-2325 4175);
WIRE 16 -1 (-3750 4325)(-2325 4325);
FORCEPROP 0 LAST CDS_PHYS_NET_NAME P3E_CPU0_PE2_SS_RXP<8>
J 0
(-3150 4325);
PAINT MONO (-3150 4325);
DISPLAY INVISIBLE (-3150 4325);
WIRE 16 -1 (-3750 4375)(-2525 4375);
FORCEPROP 0 LAST CDS_PHYS_NET_NAME P3E_CPU0_PE2_SS_RXN<8>
J 0
(-3025 4375);
PAINT MONO (-3025 4375);
DISPLAY INVISIBLE (-3025 4375);
WIRE 16 -1 (-3750 4225)(-2525 4225);
WIRE 16 -1 (-3750 4025)(-2325 4025);
WIRE 16 -1 (-5225 3975)(-4250 3975);
WIRE 16 -1 (-5225 4075)(-4250 4075);
WIRE 16 -1 (-5850 4125)(-4250 4125);
WIRE 16 -1 (-5850 4275)(-4250 4275);
WIRE 16 -1 (-4250 4425)(-5850 4425);
WIRE 16 -1 (-5225 4225)(-4250 4225);
WIRE 16 -1 (-4250 4375)(-5225 4375);
WIRE 3 2175 (-4200 4550)(-4000 4550);
WIRE 3 2175 (-4000 4600)(-4000 4550);
WIRE 3 2175 (-4200 4600)(-4200 4550);
WIRE 3 2175 (-4200 4600)(-4000 4600);
WIRE 16 -1 (-5600 1550)(-4950 1550);
FORCEPROP 2 LAST SIG_NAME JTAG_RISER_TDO_R
J 0
(-5510 1560);
DISPLAY 0.638298 (-5510 1560);
PAINT ORANGE (-5510 1560);
FORCEPROP 2 LASTPROP $XR0 245 
J 0
(-4920 1550);
DISPLAY 0.638298 (-4920 1550);
PAINT MONO (-4920 1550);
WIRE 16 -1 (-7100 1500)(-6300 1500);
FORCEPROP 2 LAST SIG_NAME JTAG_PLD_TDO_MUX_R
J 0
(-7035 1510);
DISPLAY 0.617021 (-7035 1510);
PAINT ORANGE (-7035 1510);
DOT 1 (-5500 1950);
DOT 1 (-3375 4275);
DOT 1 (-3375 4125);
DOT 1 (-3375 3975);
DOT 1 (-3375 3675);
DOT 1 (-3375 3525);
DOT 1 (-4725 4325);
DOT 1 (-4725 4175);
DOT 1 (-4725 3875);
DOT 1 (-4725 4025);
DOT 1 (-4725 3725);
DOT 1 (-4725 3275);
DOT 1 (-3375 3075);
DOT 1 (-4725 3425);
DOT 1 (-4725 3575);
DOT 1 (-3375 3225);
DOT 1 (-3375 3825);
DOT 1 (-4725 3125);
DOT 1 (-5450 1000);
DOT 1 (-5850 550);
DOT 1 (-4250 2000);
DOT 1 (-5850 1000);
DOT 1 (-3375 3375);
FORCENOTE
S=1: A=B1
(-5300 1250) 0;
DISPLAY LEFT (-5300 1250);
DISPLAY 1.021277 (-5300 1250);
PAINT PURPLE (-5300 1250);
FORCENOTE
S=0: A=B0
(-5300 1350) 0;
DISPLAY LEFT (-5300 1350);
DISPLAY 1.021277 (-5300 1350);
PAINT PURPLE (-5300 1350);
FORCENOTE
TP FAB1 NC 1225
(-4250 4775) 0;
DISPLAY LEFT (-4250 4775);
DISPLAY 1.021277 (-4250 4775);
PAINT RED (-4250 4775);
FORCENOTE
TP FAB1 NC 1225
(-4025 2750) 0;
DISPLAY LEFT (-4025 2750);
DISPLAY 1.021277 (-4025 2750);
PAINT RED (-4025 2750);
FORCENOTE
TP FAB1 ADD X8 SLOT
(-7250 2650) 0;
DISPLAY LEFT (-7250 2650);
DISPLAY 0.872340 (-7250 2650);
PAINT RED (-7250 2650);
FORCENOTE
NEW ADD
(-6350 3100) 0;
DISPLAY LEFT (-6350 3100);
DISPLAY 1.021277 (-6350 3100);
PAINT PURPLE (-6350 3100);
FORCENOTE
NEW ADD
(-6350 3250) 0;
DISPLAY LEFT (-6350 3250);
DISPLAY 1.021277 (-6350 3250);
PAINT PURPLE (-6350 3250);
FORCENOTE
TP FAB4 ADD 0OHM RES 20170111
(-6650 3325) 0;
DISPLAY LEFT (-6650 3325);
DISPLAY 0.638298 (-6650 3325);
PAINT RED (-6650 3325);
FORCENOTE
TP FAB1 SWAP USB DP/DN TO FOLLOW OCP PIN DEFINITION 0106
(-6700 2850) 0;
DISPLAY LEFT (-6700 2850);
DISPLAY 1.021277 (-6700 2850);
PAINT RED (-6700 2850);
FORCENOTE
NEW ADD
(-2150 3300) 0;
DISPLAY LEFT (-2150 3300);
DISPLAY 1.021277 (-2150 3300);
PAINT PURPLE (-2150 3300);
FORCENOTE
TP FAB4 ADD 0OHM RES 20170111
(-2825 2925) 0;
DISPLAY LEFT (-2825 2925);
DISPLAY 0.638298 (-2825 2925);
PAINT RED (-2825 2925);
FORCENOTE
TP FAB4 ADD CIRCUIT 20170111
(-4725 500) 0;
DISPLAY LEFT (-4725 500);
DISPLAY 1.021277 (-4725 500);
PAINT RED (-4725 500);
QUIT
